G04*
G04 #@! TF.GenerationSoftware,Altium Limited,Altium Designer,23.7.1 (13)*
G04*
G04 Layer_Physical_Order=2*
G04 Layer_Color=36540*
%FSLAX25Y25*%
%MOIN*%
G70*
G04*
G04 #@! TF.SameCoordinates,AF00DCEB-AC48-4C7C-91EA-99F42E284231*
G04*
G04*
G04 #@! TF.FilePolarity,Positive*
G04*
G01*
G75*
%ADD211R,0.10827X0.10827*%
%ADD212C,0.10827*%
%ADD217C,0.06299*%
%ADD236C,0.06102*%
%ADD240O,0.04921X0.04134*%
%ADD241O,0.07480X0.04724*%
%ADD242C,0.25591*%
%ADD244C,0.10000*%
%ADD246C,0.08661*%
%ADD249C,0.05906*%
%ADD250C,0.01600*%
G36*
X629735Y-364300D02*
X282941Y-364300D01*
Y-392667D01*
X200941D01*
Y-383800D01*
X197741Y-380600D01*
X194941D01*
X191741Y-383800D01*
Y-392667D01*
X149641D01*
Y-368300D01*
X145041Y-363700D01*
X137841D01*
X133341Y-368200D01*
Y-382888D01*
X103641D01*
Y-364000D01*
X29641D01*
Y-396400D01*
X-27759D01*
Y20200D01*
X-26551Y21408D01*
X629735Y21408D01*
X629735Y-364300D01*
D02*
G37*
%LPC*%
G36*
X20079Y19158D02*
X19376Y19018D01*
X18781Y18621D01*
X18383Y18025D01*
X18244Y17323D01*
X18383Y16621D01*
X18781Y16025D01*
X19376Y15627D01*
X20079Y15488D01*
X20781Y15627D01*
X21376Y16025D01*
X21774Y16621D01*
X21914Y17323D01*
X21774Y18025D01*
X21376Y18621D01*
X20781Y19018D01*
X20079Y19158D01*
D02*
G37*
G36*
X78740Y19945D02*
X78038Y19806D01*
X77442Y19408D01*
X77045Y18813D01*
X76905Y18110D01*
X77045Y17408D01*
X77442Y16813D01*
Y16652D01*
X77045Y16057D01*
X76905Y15354D01*
X77045Y14652D01*
X77442Y14057D01*
X78038Y13659D01*
X78740Y13519D01*
X79443Y13659D01*
X80038Y14057D01*
X80436Y14652D01*
X80575Y15354D01*
X80436Y16057D01*
X80038Y16652D01*
Y16813D01*
X80436Y17408D01*
X80575Y18110D01*
X80436Y18813D01*
X80038Y19408D01*
X79443Y19806D01*
X78740Y19945D01*
D02*
G37*
G36*
X142520Y15024D02*
X141817Y14885D01*
X141222Y14487D01*
X140824Y13891D01*
X140684Y13189D01*
X140824Y12487D01*
X141222Y11891D01*
X141817Y11493D01*
X142520Y11354D01*
X143222Y11493D01*
X143817Y11891D01*
X144215Y12487D01*
X144355Y13189D01*
X144215Y13891D01*
X143817Y14487D01*
X143222Y14885D01*
X142520Y15024D01*
D02*
G37*
G36*
X20079Y12465D02*
X19376Y12325D01*
X18781Y11928D01*
X18383Y11332D01*
X18244Y10630D01*
X18383Y9928D01*
X18781Y9332D01*
X19376Y8934D01*
X20079Y8795D01*
X20781Y8934D01*
X21376Y9332D01*
X21774Y9928D01*
X21914Y10630D01*
X21774Y11332D01*
X21376Y11928D01*
X20781Y12325D01*
X20079Y12465D01*
D02*
G37*
G36*
X151181Y19945D02*
X150479Y19806D01*
X149883Y19408D01*
X149486Y18813D01*
X149346Y18110D01*
X149486Y17408D01*
X149883Y16813D01*
X150479Y16415D01*
X150569Y16397D01*
Y15887D01*
X150479Y15869D01*
X149883Y15471D01*
X149486Y14876D01*
X149346Y14173D01*
X149486Y13471D01*
X149883Y12876D01*
X150479Y12478D01*
X150639Y12446D01*
X150745Y11915D01*
X150484Y11741D01*
X150086Y11145D01*
X149946Y10443D01*
X150086Y9741D01*
X150484Y9145D01*
X151079Y8748D01*
X151782Y8608D01*
X152484Y8748D01*
X153079Y9145D01*
X153477Y9741D01*
X153617Y10443D01*
X153477Y11145D01*
X153079Y11741D01*
X152484Y12139D01*
X152324Y12171D01*
X152218Y12701D01*
X152479Y12876D01*
X152877Y13471D01*
X153016Y14173D01*
X152877Y14876D01*
X152479Y15471D01*
X151883Y15869D01*
X151793Y15887D01*
Y16397D01*
X151883Y16415D01*
X152479Y16813D01*
X152877Y17408D01*
X153016Y18110D01*
X152877Y18813D01*
X152479Y19408D01*
X151883Y19806D01*
X151181Y19945D01*
D02*
G37*
G36*
X169291Y15221D02*
X168589Y15081D01*
X167994Y14683D01*
X167596Y14088D01*
X167456Y13386D01*
X167596Y12684D01*
X167994Y12088D01*
X168435Y11794D01*
X168448Y11753D01*
Y11279D01*
X168435Y11238D01*
X167994Y10943D01*
X167596Y10348D01*
X167456Y9646D01*
X167596Y8943D01*
X167994Y8348D01*
X168589Y7950D01*
X169291Y7810D01*
X169994Y7950D01*
X170589Y8348D01*
X170987Y8943D01*
X171127Y9646D01*
X170987Y10348D01*
X170589Y10943D01*
X170148Y11238D01*
X170134Y11279D01*
Y11753D01*
X170148Y11794D01*
X170589Y12088D01*
X170987Y12684D01*
X171127Y13386D01*
X170987Y14088D01*
X170589Y14683D01*
X169994Y15081D01*
X169291Y15221D01*
D02*
G37*
G36*
X159843Y11481D02*
X159140Y11341D01*
X158545Y10943D01*
X158147Y10348D01*
X158007Y9646D01*
X158147Y8943D01*
X158545Y8348D01*
X159140Y7950D01*
X159843Y7810D01*
X160545Y7950D01*
X161140Y8348D01*
X161538Y8943D01*
X161678Y9646D01*
X161538Y10348D01*
X161140Y10943D01*
X160545Y11341D01*
X159843Y11481D01*
D02*
G37*
G36*
X110589Y3424D02*
X109887Y3284D01*
X109291Y2886D01*
X108893Y2291D01*
X108858Y2112D01*
X108268Y2229D01*
X107565Y2089D01*
X106970Y1691D01*
X106572Y1096D01*
X106432Y394D01*
X106572Y-309D01*
X106970Y-904D01*
X107565Y-1302D01*
X108268Y-1442D01*
X108970Y-1302D01*
X109565Y-904D01*
X109963Y-309D01*
X109999Y-129D01*
X110589Y-246D01*
X110879Y-189D01*
X110903Y-309D01*
X111301Y-904D01*
X111896Y-1302D01*
X112598Y-1442D01*
X113301Y-1302D01*
X113896Y-904D01*
X114294Y-309D01*
X114434Y394D01*
X114294Y1096D01*
X113896Y1691D01*
X113301Y2089D01*
X112598Y2229D01*
X112308Y2171D01*
X112285Y2291D01*
X111887Y2886D01*
X111291Y3284D01*
X110589Y3424D01*
D02*
G37*
G36*
X20079Y5772D02*
X19376Y5633D01*
X18781Y5235D01*
X18383Y4639D01*
X18244Y3937D01*
X18383Y3235D01*
X18781Y2639D01*
X19376Y2241D01*
X20079Y2102D01*
X20781Y2241D01*
X21376Y2639D01*
X21774Y3235D01*
X21914Y3937D01*
X21774Y4639D01*
X21376Y5235D01*
X20781Y5633D01*
X20079Y5772D01*
D02*
G37*
G36*
X78740Y11678D02*
X78038Y11538D01*
X77442Y11140D01*
X77045Y10545D01*
X76905Y9843D01*
X77045Y9140D01*
X77442Y8545D01*
X77483Y8518D01*
Y8018D01*
X77442Y7991D01*
X77045Y7395D01*
X76905Y6693D01*
X77045Y5991D01*
X77421Y5428D01*
X77483Y5281D01*
Y4955D01*
X77421Y4808D01*
X77045Y4246D01*
X76905Y3543D01*
X77045Y2841D01*
X77442Y2246D01*
X78038Y1848D01*
X78740Y1708D01*
X79443Y1848D01*
X80038Y2246D01*
X80436Y2841D01*
X80575Y3543D01*
X80436Y4246D01*
X80060Y4808D01*
X79997Y4955D01*
Y5281D01*
X80060Y5428D01*
X80436Y5991D01*
X80575Y6693D01*
X80436Y7395D01*
X80038Y7991D01*
X79997Y8018D01*
Y8518D01*
X80038Y8545D01*
X80436Y9140D01*
X80575Y9843D01*
X80436Y10545D01*
X80038Y11140D01*
X79443Y11538D01*
X78740Y11678D01*
D02*
G37*
G36*
X552709Y13889D02*
X551452Y13766D01*
X550243Y13399D01*
X549129Y12803D01*
X548153Y12002D01*
X547351Y11025D01*
X546756Y9911D01*
X546389Y8702D01*
X546265Y7445D01*
X546389Y6188D01*
X546756Y4979D01*
X547351Y3865D01*
X548153Y2888D01*
X549129Y2087D01*
X550243Y1491D01*
X551452Y1124D01*
X552709Y1001D01*
X553967Y1124D01*
X555176Y1491D01*
X556290Y2087D01*
X557266Y2888D01*
X558068Y3865D01*
X558663Y4979D01*
X559030Y6188D01*
X559154Y7445D01*
X559030Y8702D01*
X558663Y9911D01*
X558068Y11025D01*
X557266Y12002D01*
X556290Y12803D01*
X555176Y13399D01*
X553967Y13766D01*
X552709Y13889D01*
D02*
G37*
G36*
X56693Y2895D02*
X55991Y2755D01*
X55395Y2357D01*
X54997Y1762D01*
X54858Y1060D01*
X54997Y357D01*
X55395Y-238D01*
X55991Y-636D01*
X56693Y-776D01*
X57395Y-636D01*
X57991Y-238D01*
X58389Y357D01*
X58528Y1060D01*
X58389Y1762D01*
X57991Y2357D01*
X57395Y2755D01*
X56693Y2895D01*
D02*
G37*
G36*
X61811Y2623D02*
X61109Y2483D01*
X60513Y2085D01*
X60115Y1490D01*
X59976Y787D01*
X60115Y85D01*
X60513Y-510D01*
X61109Y-908D01*
X61811Y-1048D01*
X62513Y-908D01*
X63109Y-510D01*
X63507Y85D01*
X63646Y787D01*
X63507Y1490D01*
X63109Y2085D01*
X62513Y2483D01*
X61811Y2623D01*
D02*
G37*
G36*
X141339Y2229D02*
X140636Y2089D01*
X140041Y1691D01*
X139643Y1096D01*
X139503Y394D01*
X139643Y-309D01*
X140041Y-904D01*
X140636Y-1302D01*
X141339Y-1442D01*
X142041Y-1302D01*
X142636Y-904D01*
X143034Y-309D01*
X143174Y394D01*
X143034Y1096D01*
X142636Y1691D01*
X142041Y2089D01*
X141339Y2229D01*
D02*
G37*
G36*
X365581Y18839D02*
X363855Y18704D01*
X362171Y18299D01*
X360571Y17637D01*
X359095Y16732D01*
X357779Y15608D01*
X356654Y14291D01*
X355749Y12815D01*
X355087Y11215D01*
X354683Y9532D01*
X354547Y7806D01*
X354683Y6079D01*
X355087Y4396D01*
X355749Y2796D01*
X356654Y1320D01*
X357779Y3D01*
X359095Y-1121D01*
X360571Y-2026D01*
X362171Y-2688D01*
X363855Y-3093D01*
X365581Y-3229D01*
X367307Y-3093D01*
X368990Y-2688D01*
X370590Y-2026D01*
X372066Y-1121D01*
X373383Y3D01*
X374507Y1320D01*
X375412Y2796D01*
X376075Y4396D01*
X376479Y6079D01*
X376615Y7806D01*
X376479Y9532D01*
X376075Y11215D01*
X375412Y12815D01*
X374507Y14291D01*
X373383Y15608D01*
X372066Y16732D01*
X370590Y17637D01*
X368990Y18299D01*
X367307Y18704D01*
X365581Y18839D01*
D02*
G37*
G36*
X127392D02*
X125666Y18704D01*
X123982Y18299D01*
X122382Y17637D01*
X120906Y16732D01*
X119589Y15608D01*
X118465Y14291D01*
X117560Y12815D01*
X116898Y11215D01*
X116494Y9532D01*
X116358Y7806D01*
X116494Y6079D01*
X116898Y4396D01*
X117560Y2796D01*
X118465Y1320D01*
X119589Y3D01*
X120906Y-1121D01*
X122382Y-2026D01*
X123982Y-2688D01*
X125666Y-3093D01*
X127392Y-3229D01*
X129118Y-3093D01*
X130801Y-2688D01*
X132401Y-2026D01*
X133877Y-1121D01*
X135194Y3D01*
X136319Y1320D01*
X137223Y2796D01*
X137886Y4396D01*
X138290Y6079D01*
X138426Y7806D01*
X138290Y9532D01*
X137886Y11215D01*
X137223Y12815D01*
X136319Y14291D01*
X135194Y15608D01*
X133877Y16732D01*
X132401Y17637D01*
X130801Y18299D01*
X129118Y18704D01*
X127392Y18839D01*
D02*
G37*
G36*
X162598Y261D02*
X161896Y121D01*
X161301Y-277D01*
X160903Y-872D01*
X160763Y-1575D01*
X160903Y-2277D01*
X161301Y-2873D01*
X161896Y-3270D01*
X162598Y-3410D01*
X163301Y-3270D01*
X163896Y-2873D01*
X164294Y-2277D01*
X164434Y-1575D01*
X164294Y-872D01*
X163896Y-277D01*
X163301Y121D01*
X162598Y261D01*
D02*
G37*
G36*
X194882Y4579D02*
X193799Y4436D01*
X192789Y4018D01*
X191922Y3353D01*
X191257Y2486D01*
X190839Y1477D01*
X190697Y394D01*
X190839Y-690D01*
X191257Y-1699D01*
X191922Y-2566D01*
X192789Y-3231D01*
X193799Y-3649D01*
X194882Y-3792D01*
X195965Y-3649D01*
X196975Y-3231D01*
X197841Y-2566D01*
X198507Y-1699D01*
X198925Y-690D01*
X199067Y394D01*
X198925Y1477D01*
X198507Y2486D01*
X197841Y3353D01*
X196975Y4018D01*
X195965Y4436D01*
X194882Y4579D01*
D02*
G37*
G36*
X36614Y20536D02*
X35912Y20396D01*
X35316Y19998D01*
X34919Y19403D01*
X34779Y18701D01*
X34919Y17999D01*
X35155Y17644D01*
X34949Y17093D01*
X34731Y17050D01*
X34135Y16652D01*
X33737Y16057D01*
X33598Y15354D01*
X33737Y14652D01*
X34135Y14057D01*
X34731Y13659D01*
X35237Y13558D01*
X35342Y13351D01*
X35423Y13046D01*
X35067Y12513D01*
X34927Y11811D01*
X35067Y11109D01*
X35465Y10513D01*
X35523Y10474D01*
X35521Y10229D01*
X35453Y9920D01*
X34923Y9565D01*
X34525Y8970D01*
X34385Y8268D01*
X34525Y7565D01*
X34923Y6970D01*
X35232Y6764D01*
X35316Y6224D01*
X35285Y6172D01*
X34919Y5624D01*
X34779Y4921D01*
X34919Y4219D01*
X35201Y3796D01*
X35138Y3361D01*
X35036Y3211D01*
X34529Y2873D01*
X34131Y2277D01*
X33992Y1575D01*
X34131Y872D01*
X34529Y277D01*
X35124Y-121D01*
X35213Y-138D01*
X35319Y-669D01*
X35316Y-671D01*
X34919Y-1266D01*
X34779Y-1969D01*
X34919Y-2671D01*
X35316Y-3266D01*
X35912Y-3664D01*
X36614Y-3804D01*
X37317Y-3664D01*
X37912Y-3266D01*
X38310Y-2671D01*
X38449Y-1969D01*
X38310Y-1266D01*
X37912Y-671D01*
X37317Y-273D01*
X37228Y-255D01*
X37122Y276D01*
X37124Y277D01*
X37522Y872D01*
X37662Y1575D01*
X37522Y2277D01*
X37239Y2701D01*
X37303Y3135D01*
X37405Y3285D01*
X37912Y3624D01*
X38310Y4219D01*
X38449Y4921D01*
X38310Y5624D01*
X37912Y6219D01*
X37603Y6425D01*
X37519Y6965D01*
X37549Y7017D01*
X37916Y7565D01*
X38056Y8268D01*
X37916Y8970D01*
X37518Y9565D01*
X37459Y9605D01*
X37462Y9850D01*
X37530Y10159D01*
X38060Y10513D01*
X38458Y11109D01*
X38597Y11811D01*
X38458Y12513D01*
X38060Y13109D01*
X37464Y13507D01*
X36958Y13607D01*
X36854Y13814D01*
X36773Y14119D01*
X37129Y14652D01*
X37268Y15354D01*
X37129Y16057D01*
X36892Y16411D01*
X37099Y16962D01*
X37317Y17005D01*
X37912Y17403D01*
X38310Y17999D01*
X38449Y18701D01*
X38310Y19403D01*
X37912Y19998D01*
X37317Y20396D01*
X36614Y20536D01*
D02*
G37*
G36*
X19685Y-527D02*
X18983Y-667D01*
X18387Y-1065D01*
X17989Y-1660D01*
X17850Y-2362D01*
X17989Y-3064D01*
X18387Y-3660D01*
X18983Y-4058D01*
X19685Y-4197D01*
X20387Y-4058D01*
X20983Y-3660D01*
X21381Y-3064D01*
X21520Y-2362D01*
X21381Y-1660D01*
X20983Y-1065D01*
X20387Y-667D01*
X19685Y-527D01*
D02*
G37*
G36*
X137598Y-4464D02*
X136896Y-4604D01*
X136301Y-5001D01*
X136127Y-5261D01*
X135526D01*
X135353Y-5001D01*
X134757Y-4604D01*
X134055Y-4464D01*
X133353Y-4604D01*
X132757Y-5001D01*
X132360Y-5597D01*
X132220Y-6299D01*
X132360Y-7001D01*
X132757Y-7597D01*
X133353Y-7995D01*
X134055Y-8134D01*
X134757Y-7995D01*
X135353Y-7597D01*
X135526Y-7338D01*
X136127D01*
X136301Y-7597D01*
X136896Y-7995D01*
X137598Y-8134D01*
X138301Y-7995D01*
X138896Y-7597D01*
X139294Y-7001D01*
X139434Y-6299D01*
X139294Y-5597D01*
X138896Y-5001D01*
X138301Y-4604D01*
X137598Y-4464D01*
D02*
G37*
G36*
X603110Y6128D02*
X601757Y5995D01*
X600456Y5601D01*
X599258Y4960D01*
X598207Y4098D01*
X597344Y3047D01*
X596704Y1848D01*
X596309Y548D01*
X596176Y-805D01*
X596309Y-2158D01*
X596704Y-3458D01*
X597344Y-4657D01*
X598207Y-5708D01*
X599258Y-6570D01*
X600456Y-7211D01*
X601757Y-7605D01*
X603110Y-7739D01*
X604462Y-7605D01*
X605763Y-7211D01*
X606961Y-6570D01*
X608012Y-5708D01*
X608874Y-4657D01*
X609515Y-3458D01*
X609910Y-2158D01*
X610043Y-805D01*
X609910Y548D01*
X609515Y1848D01*
X608874Y3047D01*
X608012Y4098D01*
X606961Y4960D01*
X605763Y5601D01*
X604462Y5995D01*
X603110Y6128D01*
D02*
G37*
G36*
X209449Y-1708D02*
X208747Y-1848D01*
X208151Y-2246D01*
X207753Y-2841D01*
X207614Y-3543D01*
X207749Y-4226D01*
X207360Y-4809D01*
X207220Y-5512D01*
X207360Y-6214D01*
X207548Y-6496D01*
X207360Y-6778D01*
X207220Y-7480D01*
X207360Y-8183D01*
X207757Y-8778D01*
X208353Y-9176D01*
X209055Y-9316D01*
X209757Y-9176D01*
X210353Y-8778D01*
X210751Y-8183D01*
X210890Y-7480D01*
X210751Y-6778D01*
X210562Y-6496D01*
X210751Y-6214D01*
X210890Y-5512D01*
X210755Y-4829D01*
X211144Y-4246D01*
X211284Y-3543D01*
X211144Y-2841D01*
X210747Y-2246D01*
X210151Y-1848D01*
X209449Y-1708D01*
D02*
G37*
G36*
X35731Y-8007D02*
X35029Y-8147D01*
X34434Y-8545D01*
X34036Y-9140D01*
X33896Y-9843D01*
X34036Y-10545D01*
X34434Y-11140D01*
X35029Y-11538D01*
X35731Y-11678D01*
X36434Y-11538D01*
X37029Y-11140D01*
X37427Y-10545D01*
X37567Y-9843D01*
X37427Y-9140D01*
X37029Y-8545D01*
X36434Y-8147D01*
X35731Y-8007D01*
D02*
G37*
G36*
X107832Y-8362D02*
X107130Y-8501D01*
X106535Y-8899D01*
X106137Y-9494D01*
X105997Y-10197D01*
X106137Y-10899D01*
X106535Y-11495D01*
X107130Y-11892D01*
X107832Y-12032D01*
X108535Y-11892D01*
X109130Y-11495D01*
X109528Y-10899D01*
X109668Y-10197D01*
X109528Y-9494D01*
X109130Y-8899D01*
X108535Y-8501D01*
X107832Y-8362D01*
D02*
G37*
G36*
X153543Y-8598D02*
X152841Y-8738D01*
X152246Y-9135D01*
X151848Y-9731D01*
X151708Y-10433D01*
X151848Y-11135D01*
X152246Y-11731D01*
X152841Y-12129D01*
X153543Y-12268D01*
X154246Y-12129D01*
X154841Y-11731D01*
X155239Y-11135D01*
X155379Y-10433D01*
X155239Y-9731D01*
X154841Y-9135D01*
X154246Y-8738D01*
X153543Y-8598D01*
D02*
G37*
G36*
X168110Y-8795D02*
X167408Y-8934D01*
X166813Y-9332D01*
X166415Y-9928D01*
X166275Y-10630D01*
X166415Y-11332D01*
X166813Y-11928D01*
X167408Y-12325D01*
X168110Y-12465D01*
X168813Y-12325D01*
X169408Y-11928D01*
X169806Y-11332D01*
X169946Y-10630D01*
X169806Y-9928D01*
X169408Y-9332D01*
X168813Y-8934D01*
X168110Y-8795D01*
D02*
G37*
G36*
X214567Y-9582D02*
X213865Y-9722D01*
X213269Y-10120D01*
X212871Y-10715D01*
X212732Y-11417D01*
X212871Y-12120D01*
X213269Y-12715D01*
X213865Y-13113D01*
X214567Y-13253D01*
X215269Y-13113D01*
X215865Y-12715D01*
X216263Y-12120D01*
X216402Y-11417D01*
X216263Y-10715D01*
X215865Y-10120D01*
X215269Y-9722D01*
X214567Y-9582D01*
D02*
G37*
G36*
X0Y13542D02*
X-2118Y13375D01*
X-4185Y12879D01*
X-6148Y12066D01*
X-7960Y10955D01*
X-9576Y9576D01*
X-10955Y7960D01*
X-12066Y6148D01*
X-12879Y4185D01*
X-13375Y2118D01*
X-13542Y0D01*
X-13375Y-2118D01*
X-12879Y-4185D01*
X-12066Y-6148D01*
X-10955Y-7960D01*
X-9576Y-9576D01*
X-7960Y-10955D01*
X-6148Y-12066D01*
X-4185Y-12879D01*
X-2118Y-13375D01*
X0Y-13542D01*
X2118Y-13375D01*
X4185Y-12879D01*
X6148Y-12066D01*
X7960Y-10955D01*
X9576Y-9576D01*
X10955Y-7960D01*
X12066Y-6148D01*
X12879Y-4185D01*
X13375Y-2118D01*
X13542Y0D01*
X13375Y2118D01*
X12879Y4185D01*
X12066Y6148D01*
X10955Y7960D01*
X9576Y9576D01*
X7960Y10955D01*
X6148Y12066D01*
X4185Y12879D01*
X2118Y13375D01*
X0Y13542D01*
D02*
G37*
G36*
X144685Y-9976D02*
X143983Y-10115D01*
X143387Y-10513D01*
X142990Y-11109D01*
X142850Y-11811D01*
X142990Y-12513D01*
X143387Y-13109D01*
X143983Y-13507D01*
X144685Y-13646D01*
X145387Y-13507D01*
X145983Y-13109D01*
X146381Y-12513D01*
X146520Y-11811D01*
X146381Y-11109D01*
X145983Y-10513D01*
X145387Y-10115D01*
X144685Y-9976D01*
D02*
G37*
G36*
X127165Y-10763D02*
X126463Y-10903D01*
X125868Y-11301D01*
X125470Y-11896D01*
X125330Y-12598D01*
X125470Y-13301D01*
X125868Y-13896D01*
X126463Y-14294D01*
X127165Y-14434D01*
X127868Y-14294D01*
X128463Y-13896D01*
X128861Y-13301D01*
X129001Y-12598D01*
X128861Y-11896D01*
X128463Y-11301D01*
X127868Y-10903D01*
X127165Y-10763D01*
D02*
G37*
G36*
X162598Y-7614D02*
X161896Y-7753D01*
X161301Y-8151D01*
X160903Y-8747D01*
X160763Y-9449D01*
X160903Y-10151D01*
X161301Y-10746D01*
X161742Y-11041D01*
X161756Y-11082D01*
Y-11556D01*
X161742Y-11597D01*
X161301Y-11891D01*
X160903Y-12487D01*
X160763Y-13189D01*
X160903Y-13891D01*
X161301Y-14487D01*
X161896Y-14885D01*
X162598Y-15024D01*
X163301Y-14885D01*
X163896Y-14487D01*
X164294Y-13891D01*
X164434Y-13189D01*
X164294Y-12487D01*
X163896Y-11891D01*
X163455Y-11597D01*
X163441Y-11556D01*
Y-11082D01*
X163455Y-11041D01*
X163896Y-10746D01*
X164294Y-10151D01*
X164434Y-9449D01*
X164294Y-8747D01*
X163896Y-8151D01*
X163301Y-7753D01*
X162598Y-7614D01*
D02*
G37*
G36*
X552709Y-2611D02*
X551452Y-2734D01*
X550243Y-3101D01*
X549129Y-3697D01*
X548153Y-4498D01*
X547351Y-5475D01*
X546756Y-6589D01*
X546389Y-7798D01*
X546265Y-9055D01*
X546389Y-10312D01*
X546756Y-11521D01*
X547351Y-12635D01*
X548153Y-13612D01*
X549129Y-14413D01*
X550243Y-15009D01*
X551452Y-15376D01*
X552709Y-15499D01*
X553967Y-15376D01*
X555176Y-15009D01*
X556290Y-14413D01*
X557266Y-13612D01*
X558068Y-12635D01*
X558663Y-11521D01*
X559030Y-10312D01*
X559154Y-9055D01*
X559030Y-7798D01*
X558663Y-6589D01*
X558068Y-5475D01*
X557266Y-4498D01*
X556290Y-3697D01*
X555176Y-3101D01*
X553967Y-2734D01*
X552709Y-2611D01*
D02*
G37*
G36*
X211811Y-14700D02*
X211109Y-14840D01*
X210513Y-15238D01*
X210116Y-15833D01*
X209976Y-16535D01*
X210116Y-17238D01*
X210513Y-17833D01*
X211109Y-18231D01*
X211811Y-18371D01*
X212513Y-18231D01*
X213109Y-17833D01*
X213507Y-17238D01*
X213646Y-16535D01*
X213507Y-15833D01*
X213109Y-15238D01*
X212513Y-14840D01*
X211811Y-14700D01*
D02*
G37*
G36*
X118898Y-15094D02*
X118195Y-15234D01*
X117600Y-15631D01*
X117202Y-16227D01*
X117062Y-16929D01*
X117202Y-17631D01*
X117600Y-18227D01*
X118195Y-18625D01*
X118898Y-18764D01*
X119600Y-18625D01*
X120195Y-18227D01*
X120593Y-17631D01*
X120733Y-16929D01*
X120593Y-16227D01*
X120195Y-15631D01*
X119600Y-15234D01*
X118898Y-15094D01*
D02*
G37*
G36*
X85853Y-11944D02*
X85151Y-12084D01*
X84556Y-12482D01*
X84158Y-13077D01*
X84018Y-13780D01*
X84158Y-14482D01*
X84556Y-15077D01*
X84583Y-15096D01*
Y-15596D01*
X84529Y-15631D01*
X84131Y-16227D01*
X83991Y-16929D01*
X84131Y-17631D01*
X84529Y-18227D01*
X85124Y-18625D01*
X85827Y-18764D01*
X86529Y-18625D01*
X87125Y-18227D01*
X87522Y-17631D01*
X87662Y-16929D01*
X87522Y-16227D01*
X87125Y-15631D01*
X87097Y-15613D01*
Y-15113D01*
X87151Y-15077D01*
X87549Y-14482D01*
X87688Y-13780D01*
X87549Y-13077D01*
X87151Y-12482D01*
X86556Y-12084D01*
X85853Y-11944D01*
D02*
G37*
G36*
X35731Y-17062D02*
X35029Y-17202D01*
X34434Y-17600D01*
X34036Y-18195D01*
X33896Y-18898D01*
X34036Y-19600D01*
X34434Y-20195D01*
X35029Y-20593D01*
X35731Y-20733D01*
X36434Y-20593D01*
X37029Y-20195D01*
X37427Y-19600D01*
X37567Y-18898D01*
X37427Y-18195D01*
X37029Y-17600D01*
X36434Y-17202D01*
X35731Y-17062D01*
D02*
G37*
G36*
X500787Y-18244D02*
X500085Y-18383D01*
X499490Y-18781D01*
X499092Y-19376D01*
X498952Y-20079D01*
X499092Y-20781D01*
X499490Y-21376D01*
X500085Y-21774D01*
X500787Y-21914D01*
X501490Y-21774D01*
X502085Y-21376D01*
X502483Y-20781D01*
X502623Y-20079D01*
X502483Y-19376D01*
X502085Y-18781D01*
X501490Y-18383D01*
X500787Y-18244D01*
D02*
G37*
G36*
X601181Y-21787D02*
X600479Y-21926D01*
X599883Y-22324D01*
X599485Y-22920D01*
X599468Y-23010D01*
X598958D01*
X598940Y-22920D01*
X598542Y-22324D01*
X597946Y-21926D01*
X597244Y-21787D01*
X596542Y-21926D01*
X595946Y-22324D01*
X595548Y-22920D01*
X595409Y-23622D01*
X595548Y-24324D01*
X595925Y-24887D01*
X595987Y-25034D01*
Y-25360D01*
X595925Y-25507D01*
X595548Y-26069D01*
X595409Y-26772D01*
X595548Y-27474D01*
X595946Y-28069D01*
X595987Y-28096D01*
Y-28596D01*
X595946Y-28624D01*
X595548Y-29219D01*
X595409Y-29921D01*
X595548Y-30624D01*
X595946Y-31219D01*
X596542Y-31617D01*
X597244Y-31756D01*
X597946Y-31617D01*
X598542Y-31219D01*
X598940Y-30624D01*
X598958Y-30533D01*
X599468D01*
X599485Y-30624D01*
X599883Y-31219D01*
X600479Y-31617D01*
X601181Y-31756D01*
X601883Y-31617D01*
X602479Y-31219D01*
X602877Y-30624D01*
X603016Y-29921D01*
X602877Y-29219D01*
X602479Y-28624D01*
X602438Y-28596D01*
Y-28096D01*
X602479Y-28069D01*
X602877Y-27474D01*
X603016Y-26772D01*
X602877Y-26069D01*
X602501Y-25507D01*
X602438Y-25360D01*
Y-25034D01*
X602501Y-24887D01*
X602877Y-24324D01*
X603016Y-23622D01*
X602877Y-22920D01*
X602479Y-22324D01*
X601883Y-21926D01*
X601181Y-21787D01*
D02*
G37*
G36*
X211024Y-19425D02*
X210321Y-19564D01*
X209726Y-19962D01*
X209328Y-20558D01*
X209188Y-21260D01*
X209328Y-21962D01*
X209726Y-22558D01*
X210321Y-22955D01*
X211024Y-23095D01*
X211726Y-22955D01*
X212321Y-22558D01*
X212719Y-21962D01*
X212859Y-21260D01*
X212719Y-20558D01*
X212321Y-19962D01*
X211726Y-19564D01*
X211024Y-19425D01*
D02*
G37*
G36*
X47441D02*
X46739Y-19564D01*
X46143Y-19962D01*
X45745Y-20558D01*
X45606Y-21260D01*
X45745Y-21962D01*
X46143Y-22558D01*
X46739Y-22955D01*
X47441Y-23095D01*
X48143Y-22955D01*
X48739Y-22558D01*
X49136Y-21962D01*
X49276Y-21260D01*
X49136Y-20558D01*
X48739Y-19962D01*
X48143Y-19564D01*
X47441Y-19425D01*
D02*
G37*
G36*
X116929Y-19818D02*
X116227Y-19958D01*
X115631Y-20356D01*
X115234Y-20951D01*
X115094Y-21654D01*
X115234Y-22356D01*
X115631Y-22951D01*
X116227Y-23349D01*
X116929Y-23489D01*
X117631Y-23349D01*
X118227Y-22951D01*
X118625Y-22356D01*
X118764Y-21654D01*
X118625Y-20951D01*
X118227Y-20356D01*
X117631Y-19958D01*
X116929Y-19818D01*
D02*
G37*
G36*
X138297Y-19551D02*
X137323Y-19745D01*
X136498Y-20297D01*
X135946Y-21122D01*
X135752Y-22096D01*
X135946Y-23070D01*
X136498Y-23896D01*
X137323Y-24447D01*
X138297Y-24641D01*
X139271Y-24447D01*
X140097Y-23896D01*
X140648Y-23070D01*
X140842Y-22096D01*
X140648Y-21122D01*
X140097Y-20297D01*
X139271Y-19745D01*
X138297Y-19551D01*
D02*
G37*
G36*
X505118Y-18244D02*
X504416Y-18383D01*
X503820Y-18781D01*
X503422Y-19376D01*
X503283Y-20079D01*
X503422Y-20781D01*
X503820Y-21376D01*
X504416Y-21774D01*
X504506Y-21792D01*
Y-22302D01*
X504416Y-22320D01*
X503820Y-22718D01*
X503422Y-23313D01*
X503283Y-24016D01*
X503422Y-24718D01*
X503820Y-25313D01*
X504416Y-25711D01*
X505118Y-25851D01*
X505820Y-25711D01*
X506416Y-25313D01*
X506814Y-24718D01*
X506953Y-24016D01*
X506814Y-23313D01*
X506416Y-22718D01*
X505820Y-22320D01*
X505730Y-22302D01*
Y-21792D01*
X505820Y-21774D01*
X506416Y-21376D01*
X506814Y-20781D01*
X506953Y-20079D01*
X506814Y-19376D01*
X506416Y-18781D01*
X505820Y-18383D01*
X505118Y-18244D01*
D02*
G37*
G36*
X496457D02*
X495754Y-18383D01*
X495159Y-18781D01*
X494761Y-19376D01*
X494621Y-20079D01*
X494761Y-20781D01*
X495159Y-21376D01*
X495754Y-21774D01*
X495845Y-21792D01*
Y-22302D01*
X495754Y-22320D01*
X495159Y-22718D01*
X494761Y-23313D01*
X494621Y-24016D01*
X494761Y-24718D01*
X495159Y-25313D01*
X495754Y-25711D01*
X496457Y-25851D01*
X497159Y-25711D01*
X497754Y-25313D01*
X498152Y-24718D01*
X498292Y-24016D01*
X498152Y-23313D01*
X497754Y-22718D01*
X497159Y-22320D01*
X497068Y-22302D01*
Y-21792D01*
X497159Y-21774D01*
X497754Y-21376D01*
X498152Y-20781D01*
X498292Y-20079D01*
X498152Y-19376D01*
X497754Y-18781D01*
X497159Y-18383D01*
X496457Y-18244D01*
D02*
G37*
G36*
X500787Y-22574D02*
X500085Y-22714D01*
X499490Y-23112D01*
X499092Y-23707D01*
X498952Y-24409D01*
X499092Y-25112D01*
X499490Y-25707D01*
X500085Y-26105D01*
X500787Y-26245D01*
X501490Y-26105D01*
X502085Y-25707D01*
X502483Y-25112D01*
X502623Y-24409D01*
X502483Y-23707D01*
X502085Y-23112D01*
X501490Y-22714D01*
X500787Y-22574D01*
D02*
G37*
G36*
X216535Y-23362D02*
X215833Y-23501D01*
X215238Y-23899D01*
X214840Y-24495D01*
X214700Y-25197D01*
X214840Y-25899D01*
X215238Y-26495D01*
X215833Y-26892D01*
X216535Y-27032D01*
X217238Y-26892D01*
X217833Y-26495D01*
X218231Y-25899D01*
X218371Y-25197D01*
X218231Y-24495D01*
X217833Y-23899D01*
X217238Y-23501D01*
X216535Y-23362D01*
D02*
G37*
G36*
X161417Y-24149D02*
X160715Y-24289D01*
X160120Y-24687D01*
X159722Y-25282D01*
X159582Y-25984D01*
X159722Y-26687D01*
X160120Y-27282D01*
X160715Y-27680D01*
X161417Y-27819D01*
X162120Y-27680D01*
X162715Y-27282D01*
X163113Y-26687D01*
X163253Y-25984D01*
X163113Y-25282D01*
X162715Y-24687D01*
X162120Y-24289D01*
X161417Y-24149D01*
D02*
G37*
G36*
X155328Y-24198D02*
X154625Y-24338D01*
X154030Y-24735D01*
X153632Y-25331D01*
X153492Y-26033D01*
X153632Y-26735D01*
X154030Y-27331D01*
X154625Y-27729D01*
X155328Y-27868D01*
X156030Y-27729D01*
X156625Y-27331D01*
X157023Y-26735D01*
X157163Y-26033D01*
X157023Y-25331D01*
X156625Y-24735D01*
X156030Y-24338D01*
X155328Y-24198D01*
D02*
G37*
G36*
X122539D02*
X121837Y-24338D01*
X121241Y-24735D01*
X120844Y-25331D01*
X120704Y-26033D01*
X120844Y-26735D01*
X121241Y-27331D01*
X121837Y-27729D01*
X122539Y-27868D01*
X123241Y-27729D01*
X123837Y-27331D01*
X124235Y-26735D01*
X124374Y-26033D01*
X124235Y-25331D01*
X123837Y-24735D01*
X123241Y-24338D01*
X122539Y-24198D01*
D02*
G37*
G36*
X47441Y-25527D02*
X46739Y-25667D01*
X46143Y-26065D01*
X45745Y-26660D01*
X45606Y-27362D01*
X45745Y-28065D01*
X46143Y-28660D01*
X46739Y-29058D01*
X47441Y-29197D01*
X48143Y-29058D01*
X48739Y-28660D01*
X49136Y-28065D01*
X49276Y-27362D01*
X49136Y-26660D01*
X48739Y-26065D01*
X48143Y-25667D01*
X47441Y-25527D01*
D02*
G37*
G36*
X39764Y-24149D02*
X39061Y-24289D01*
X38466Y-24687D01*
X38068Y-25282D01*
X37929Y-25984D01*
X38068Y-26687D01*
X38466Y-27282D01*
X38725Y-27455D01*
Y-28057D01*
X38466Y-28230D01*
X38068Y-28825D01*
X37929Y-29528D01*
X38068Y-30230D01*
X38466Y-30825D01*
X39061Y-31223D01*
X39764Y-31363D01*
X40466Y-31223D01*
X41061Y-30825D01*
X41459Y-30230D01*
X41599Y-29528D01*
X41459Y-28825D01*
X41061Y-28230D01*
X40802Y-28057D01*
Y-27455D01*
X41061Y-27282D01*
X41459Y-26687D01*
X41599Y-25984D01*
X41459Y-25282D01*
X41061Y-24687D01*
X40466Y-24289D01*
X39764Y-24149D01*
D02*
G37*
G36*
X100394Y-28480D02*
X99691Y-28619D01*
X99096Y-29017D01*
X98698Y-29613D01*
X98558Y-30315D01*
X98698Y-31017D01*
X99096Y-31613D01*
X99691Y-32010D01*
X100394Y-32150D01*
X101096Y-32010D01*
X101691Y-31613D01*
X102089Y-31017D01*
X102229Y-30315D01*
X102089Y-29613D01*
X101691Y-29017D01*
X101096Y-28619D01*
X100394Y-28480D01*
D02*
G37*
G36*
X121653Y-29661D02*
X120951Y-29801D01*
X120356Y-30198D01*
X119958Y-30794D01*
X119818Y-31496D01*
X119958Y-32198D01*
X120356Y-32794D01*
X120951Y-33192D01*
X121653Y-33331D01*
X122356Y-33192D01*
X122951Y-32794D01*
X123349Y-32198D01*
X123489Y-31496D01*
X123349Y-30794D01*
X122951Y-30198D01*
X122356Y-29801D01*
X121653Y-29661D01*
D02*
G37*
G36*
X226378Y-30842D02*
X225676Y-30982D01*
X225080Y-31380D01*
X224682Y-31975D01*
X224543Y-32677D01*
X224682Y-33380D01*
X225080Y-33975D01*
X225676Y-34373D01*
X226378Y-34512D01*
X227080Y-34373D01*
X227676Y-33975D01*
X228074Y-33380D01*
X228213Y-32677D01*
X228074Y-31975D01*
X227676Y-31380D01*
X227080Y-30982D01*
X226378Y-30842D01*
D02*
G37*
G36*
X155427Y-32072D02*
X154724Y-32212D01*
X154129Y-32609D01*
X153731Y-33205D01*
X153592Y-33907D01*
X153731Y-34609D01*
X154129Y-35205D01*
X154724Y-35603D01*
X155427Y-35742D01*
X156129Y-35603D01*
X156725Y-35205D01*
X157122Y-34609D01*
X157262Y-33907D01*
X157122Y-33205D01*
X156725Y-32609D01*
X156129Y-32212D01*
X155427Y-32072D01*
D02*
G37*
G36*
X43701Y-32810D02*
X42998Y-32950D01*
X42403Y-33348D01*
X42005Y-33943D01*
X41866Y-34646D01*
X42005Y-35348D01*
X42403Y-35943D01*
X42998Y-36341D01*
X43701Y-36481D01*
X44403Y-36341D01*
X44998Y-35943D01*
X45396Y-35348D01*
X45536Y-34646D01*
X45396Y-33943D01*
X44998Y-33348D01*
X44403Y-32950D01*
X43701Y-32810D01*
D02*
G37*
G36*
X91339Y-33204D02*
X90636Y-33344D01*
X90041Y-33742D01*
X89643Y-34337D01*
X89503Y-35039D01*
X89643Y-35742D01*
X90041Y-36337D01*
X90636Y-36735D01*
X91339Y-36875D01*
X92041Y-36735D01*
X92636Y-36337D01*
X93034Y-35742D01*
X93174Y-35039D01*
X93034Y-34337D01*
X92636Y-33742D01*
X92041Y-33344D01*
X91339Y-33204D01*
D02*
G37*
G36*
X295276Y-33598D02*
X294573Y-33737D01*
X293978Y-34135D01*
X293580Y-34731D01*
X293440Y-35433D01*
X293580Y-36135D01*
X293978Y-36731D01*
X294573Y-37129D01*
X295276Y-37268D01*
X295978Y-37129D01*
X296573Y-36731D01*
X296971Y-36135D01*
X297111Y-35433D01*
X296971Y-34731D01*
X296573Y-34135D01*
X295978Y-33737D01*
X295276Y-33598D01*
D02*
G37*
G36*
X290945D02*
X290243Y-33737D01*
X289647Y-34135D01*
X289249Y-34731D01*
X289110Y-35433D01*
X289249Y-36135D01*
X289647Y-36731D01*
X290243Y-37129D01*
X290945Y-37268D01*
X291647Y-37129D01*
X292243Y-36731D01*
X292640Y-36135D01*
X292780Y-35433D01*
X292640Y-34731D01*
X292243Y-34135D01*
X291647Y-33737D01*
X290945Y-33598D01*
D02*
G37*
G36*
X61417Y-33906D02*
X60715Y-34045D01*
X60120Y-34443D01*
X59722Y-35039D01*
X59582Y-35741D01*
X59722Y-36443D01*
X60120Y-37038D01*
X60715Y-37436D01*
X61417Y-37576D01*
X62120Y-37436D01*
X62715Y-37038D01*
X63113Y-36443D01*
X63253Y-35741D01*
X63113Y-35039D01*
X62715Y-34443D01*
X62120Y-34045D01*
X61417Y-33906D01*
D02*
G37*
G36*
X101181Y-36747D02*
X100479Y-36887D01*
X99883Y-37285D01*
X99485Y-37880D01*
X99346Y-38583D01*
X99485Y-39285D01*
X99883Y-39880D01*
X100479Y-40278D01*
X101181Y-40418D01*
X101883Y-40278D01*
X102479Y-39880D01*
X102877Y-39285D01*
X103016Y-38583D01*
X102877Y-37880D01*
X102479Y-37285D01*
X101883Y-36887D01*
X101181Y-36747D01*
D02*
G37*
G36*
X463779Y-37535D02*
X463077Y-37674D01*
X462482Y-38072D01*
X462084Y-38668D01*
X461944Y-39370D01*
X462084Y-40072D01*
X462482Y-40668D01*
X463077Y-41066D01*
X463779Y-41205D01*
X464482Y-41066D01*
X465077Y-40668D01*
X465475Y-40072D01*
X465615Y-39370D01*
X465475Y-38668D01*
X465077Y-38072D01*
X464482Y-37674D01*
X463779Y-37535D01*
D02*
G37*
G36*
X458661D02*
X457959Y-37674D01*
X457364Y-38072D01*
X456966Y-38668D01*
X456826Y-39370D01*
X456966Y-40072D01*
X457364Y-40668D01*
X457959Y-41066D01*
X458661Y-41205D01*
X459364Y-41066D01*
X459959Y-40668D01*
X460357Y-40072D01*
X460497Y-39370D01*
X460357Y-38668D01*
X459959Y-38072D01*
X459364Y-37674D01*
X458661Y-37535D01*
D02*
G37*
G36*
X86614D02*
X85912Y-37674D01*
X85316Y-38072D01*
X84919Y-38668D01*
X84779Y-39370D01*
X84919Y-40072D01*
X85316Y-40668D01*
X85912Y-41066D01*
X86614Y-41205D01*
X87317Y-41066D01*
X87912Y-40668D01*
X88310Y-40072D01*
X88449Y-39370D01*
X88310Y-38668D01*
X87912Y-38072D01*
X87317Y-37674D01*
X86614Y-37535D01*
D02*
G37*
G36*
X468898Y-37929D02*
X468195Y-38068D01*
X467600Y-38466D01*
X467202Y-39061D01*
X467062Y-39764D01*
X467202Y-40466D01*
X467600Y-41061D01*
X468195Y-41459D01*
X468898Y-41599D01*
X469600Y-41459D01*
X470195Y-41061D01*
X470593Y-40466D01*
X470733Y-39764D01*
X470593Y-39061D01*
X470195Y-38466D01*
X469600Y-38068D01*
X468898Y-37929D01*
D02*
G37*
G36*
X220866D02*
X220164Y-38068D01*
X219568Y-38466D01*
X219171Y-39061D01*
X219031Y-39764D01*
X219171Y-40466D01*
X219568Y-41061D01*
X220164Y-41459D01*
X220866Y-41599D01*
X221568Y-41459D01*
X222164Y-41061D01*
X222562Y-40466D01*
X222701Y-39764D01*
X222562Y-39061D01*
X222164Y-38466D01*
X221568Y-38068D01*
X220866Y-37929D01*
D02*
G37*
G36*
X295276Y-39110D02*
X294573Y-39249D01*
X293978Y-39647D01*
X293580Y-40243D01*
X293440Y-40945D01*
X293580Y-41647D01*
X293978Y-42243D01*
X294573Y-42640D01*
X295276Y-42780D01*
X295978Y-42640D01*
X296573Y-42243D01*
X296971Y-41647D01*
X297111Y-40945D01*
X296971Y-40243D01*
X296573Y-39647D01*
X295978Y-39249D01*
X295276Y-39110D01*
D02*
G37*
G36*
X290945D02*
X290243Y-39249D01*
X289647Y-39647D01*
X289249Y-40243D01*
X289110Y-40945D01*
X289249Y-41647D01*
X289647Y-42243D01*
X290243Y-42640D01*
X290945Y-42780D01*
X291647Y-42640D01*
X292243Y-42243D01*
X292640Y-41647D01*
X292780Y-40945D01*
X292640Y-40243D01*
X292243Y-39647D01*
X291647Y-39249D01*
X290945Y-39110D01*
D02*
G37*
G36*
X118504D02*
X117802Y-39249D01*
X117206Y-39647D01*
X116808Y-40243D01*
X116669Y-40945D01*
X116808Y-41647D01*
X117206Y-42243D01*
X117802Y-42640D01*
X118504Y-42780D01*
X119206Y-42640D01*
X119802Y-42243D01*
X120200Y-41647D01*
X120339Y-40945D01*
X120200Y-40243D01*
X119802Y-39647D01*
X119206Y-39249D01*
X118504Y-39110D01*
D02*
G37*
G36*
X157087Y-39897D02*
X156384Y-40037D01*
X155789Y-40435D01*
X155391Y-41030D01*
X155251Y-41732D01*
X155391Y-42435D01*
X155789Y-43030D01*
X156384Y-43428D01*
X157087Y-43567D01*
X157789Y-43428D01*
X158384Y-43030D01*
X158782Y-42435D01*
X158922Y-41732D01*
X158782Y-41030D01*
X158384Y-40435D01*
X157789Y-40037D01*
X157087Y-39897D01*
D02*
G37*
G36*
X544095Y-40291D02*
X543392Y-40430D01*
X542797Y-40828D01*
X542399Y-41424D01*
X542259Y-42126D01*
X542399Y-42828D01*
X542797Y-43424D01*
X543392Y-43821D01*
X544095Y-43961D01*
X544797Y-43821D01*
X545392Y-43424D01*
X545790Y-42828D01*
X545930Y-42126D01*
X545790Y-41424D01*
X545392Y-40828D01*
X544797Y-40430D01*
X544095Y-40291D01*
D02*
G37*
G36*
X539764D02*
X539061Y-40430D01*
X538466Y-40828D01*
X538068Y-41424D01*
X537928Y-42126D01*
X538068Y-42828D01*
X538466Y-43424D01*
X539061Y-43821D01*
X539764Y-43961D01*
X540466Y-43821D01*
X541061Y-43424D01*
X541459Y-42828D01*
X541599Y-42126D01*
X541459Y-41424D01*
X541061Y-40828D01*
X540466Y-40430D01*
X539764Y-40291D01*
D02*
G37*
G36*
X215354D02*
X214652Y-40430D01*
X214057Y-40828D01*
X213659Y-41424D01*
X213519Y-42126D01*
X213659Y-42828D01*
X214057Y-43424D01*
X214652Y-43821D01*
X215354Y-43961D01*
X216057Y-43821D01*
X216652Y-43424D01*
X217050Y-42828D01*
X217190Y-42126D01*
X217050Y-41424D01*
X216652Y-40828D01*
X216057Y-40430D01*
X215354Y-40291D01*
D02*
G37*
G36*
X324016Y-33992D02*
X323313Y-34131D01*
X322718Y-34529D01*
X322320Y-35124D01*
X322181Y-35827D01*
X322320Y-36529D01*
X322718Y-37124D01*
X323313Y-37522D01*
X323404Y-37540D01*
Y-38050D01*
X323313Y-38068D01*
X322718Y-38466D01*
X322320Y-39061D01*
X322181Y-39764D01*
X322320Y-40466D01*
X322718Y-41061D01*
X322759Y-41089D01*
Y-41589D01*
X322718Y-41616D01*
X322320Y-42211D01*
X322181Y-42913D01*
X322320Y-43616D01*
X322718Y-44211D01*
X323313Y-44609D01*
X324016Y-44749D01*
X324718Y-44609D01*
X325313Y-44211D01*
X325711Y-43616D01*
X325851Y-42913D01*
X325711Y-42211D01*
X325313Y-41616D01*
X325273Y-41589D01*
Y-41089D01*
X325313Y-41061D01*
X325711Y-40466D01*
X325851Y-39764D01*
X325711Y-39061D01*
X325313Y-38466D01*
X324718Y-38068D01*
X324627Y-38050D01*
Y-37540D01*
X324718Y-37522D01*
X325313Y-37124D01*
X325711Y-36529D01*
X325851Y-35827D01*
X325711Y-35124D01*
X325313Y-34529D01*
X324718Y-34131D01*
X324016Y-33992D01*
D02*
G37*
G36*
X318898D02*
X318195Y-34131D01*
X317600Y-34529D01*
X317202Y-35124D01*
X317062Y-35827D01*
X317202Y-36529D01*
X317600Y-37124D01*
X318195Y-37522D01*
X318286Y-37540D01*
Y-38050D01*
X318195Y-38068D01*
X317600Y-38466D01*
X317202Y-39061D01*
X317062Y-39764D01*
X317202Y-40466D01*
X317600Y-41061D01*
X317859Y-41235D01*
Y-41836D01*
X317600Y-42009D01*
X317202Y-42605D01*
X317062Y-43307D01*
X317202Y-44009D01*
X317600Y-44605D01*
X318195Y-45003D01*
X318898Y-45142D01*
X319600Y-45003D01*
X320195Y-44605D01*
X320593Y-44009D01*
X320733Y-43307D01*
X320593Y-42605D01*
X320195Y-42009D01*
X319936Y-41836D01*
Y-41235D01*
X320195Y-41061D01*
X320593Y-40466D01*
X320733Y-39764D01*
X320593Y-39061D01*
X320195Y-38466D01*
X319600Y-38068D01*
X319509Y-38050D01*
Y-37540D01*
X319600Y-37522D01*
X320195Y-37124D01*
X320593Y-36529D01*
X320733Y-35827D01*
X320593Y-35124D01*
X320195Y-34529D01*
X319600Y-34131D01*
X318898Y-33992D01*
D02*
G37*
G36*
X37402Y-41520D02*
X36699Y-41660D01*
X36104Y-42058D01*
X35706Y-42653D01*
X35566Y-43355D01*
X35706Y-44058D01*
X36104Y-44653D01*
X36699Y-45051D01*
X37402Y-45191D01*
X38104Y-45051D01*
X38699Y-44653D01*
X39097Y-44058D01*
X39237Y-43355D01*
X39097Y-42653D01*
X38699Y-42058D01*
X38104Y-41660D01*
X37402Y-41520D01*
D02*
G37*
G36*
X88583Y-44621D02*
X87880Y-44761D01*
X87285Y-45159D01*
X86980Y-45615D01*
X86528Y-45677D01*
X86402Y-45649D01*
X86337Y-45553D01*
X85742Y-45155D01*
X85039Y-45015D01*
X84337Y-45155D01*
X83742Y-45553D01*
X83344Y-46148D01*
X83204Y-46850D01*
X83344Y-47553D01*
X83742Y-48148D01*
X84337Y-48546D01*
X84428Y-48564D01*
Y-49074D01*
X84337Y-49092D01*
X83742Y-49490D01*
X83344Y-50085D01*
X83204Y-50787D01*
X83344Y-51490D01*
X83742Y-52085D01*
X83782Y-52112D01*
Y-52612D01*
X83742Y-52639D01*
X83344Y-53235D01*
X83204Y-53937D01*
X83344Y-54639D01*
X83742Y-55235D01*
X84337Y-55633D01*
X84890Y-55743D01*
X84779Y-56299D01*
X84919Y-57002D01*
X85316Y-57597D01*
X85912Y-57995D01*
X86614Y-58135D01*
X87317Y-57995D01*
X87912Y-57597D01*
X88310Y-57002D01*
X88449Y-56299D01*
X88432Y-56213D01*
X88781Y-55733D01*
X89285Y-55633D01*
X89880Y-55235D01*
X90278Y-54639D01*
X90418Y-53937D01*
X90278Y-53235D01*
X89880Y-52639D01*
X89840Y-52612D01*
Y-52112D01*
X89880Y-52085D01*
X90278Y-51490D01*
X90418Y-50787D01*
X90278Y-50085D01*
X89880Y-49490D01*
X89285Y-49092D01*
X88583Y-48952D01*
X87880Y-49092D01*
X87285Y-49490D01*
X87112Y-49749D01*
X86510D01*
X86337Y-49490D01*
X85742Y-49092D01*
X85651Y-49074D01*
Y-48564D01*
X85742Y-48546D01*
X86337Y-48148D01*
X86642Y-47692D01*
X87094Y-47630D01*
X87220Y-47658D01*
X87285Y-47754D01*
X87880Y-48152D01*
X88583Y-48292D01*
X89285Y-48152D01*
X89880Y-47754D01*
X90278Y-47159D01*
X90418Y-46457D01*
X90278Y-45754D01*
X89880Y-45159D01*
X89285Y-44761D01*
X88583Y-44621D01*
D02*
G37*
G36*
X458661Y-42259D02*
X457959Y-42399D01*
X457364Y-42797D01*
X456966Y-43392D01*
X456826Y-44094D01*
X456966Y-44797D01*
X457364Y-45392D01*
X457959Y-45790D01*
X458661Y-45930D01*
X459364Y-45790D01*
X459959Y-45392D01*
X460357Y-44797D01*
X460497Y-44094D01*
X460357Y-43392D01*
X459959Y-42797D01*
X459364Y-42399D01*
X458661Y-42259D01*
D02*
G37*
G36*
X210236D02*
X209534Y-42399D01*
X208939Y-42797D01*
X208541Y-43392D01*
X208401Y-44094D01*
X208541Y-44797D01*
X208939Y-45392D01*
X209534Y-45790D01*
X210236Y-45930D01*
X210939Y-45790D01*
X211534Y-45392D01*
X211932Y-44797D01*
X212071Y-44094D01*
X211932Y-43392D01*
X211534Y-42797D01*
X210939Y-42399D01*
X210236Y-42259D01*
D02*
G37*
G36*
X468504Y-42653D02*
X467802Y-42793D01*
X467206Y-43191D01*
X466808Y-43786D01*
X466669Y-44488D01*
X466808Y-45191D01*
X467206Y-45786D01*
X467802Y-46184D01*
X468504Y-46323D01*
X469206Y-46184D01*
X469802Y-45786D01*
X470199Y-45191D01*
X470339Y-44488D01*
X470199Y-43786D01*
X469802Y-43191D01*
X469206Y-42793D01*
X468504Y-42653D01*
D02*
G37*
G36*
X463779D02*
X463077Y-42793D01*
X462482Y-43191D01*
X462084Y-43786D01*
X461944Y-44488D01*
X462084Y-45191D01*
X462482Y-45786D01*
X463077Y-46184D01*
X463779Y-46323D01*
X464482Y-46184D01*
X465077Y-45786D01*
X465475Y-45191D01*
X465615Y-44488D01*
X465475Y-43786D01*
X465077Y-43191D01*
X464482Y-42793D01*
X463779Y-42653D01*
D02*
G37*
G36*
X295669Y-43440D02*
X294967Y-43580D01*
X294372Y-43978D01*
X293974Y-44573D01*
X293834Y-45276D01*
X293974Y-45978D01*
X294372Y-46573D01*
X294967Y-46971D01*
X295669Y-47111D01*
X296372Y-46971D01*
X296967Y-46573D01*
X297365Y-45978D01*
X297504Y-45276D01*
X297365Y-44573D01*
X296967Y-43978D01*
X296372Y-43580D01*
X295669Y-43440D01*
D02*
G37*
G36*
X290945D02*
X290243Y-43580D01*
X289647Y-43978D01*
X289249Y-44573D01*
X289110Y-45276D01*
X289249Y-45978D01*
X289647Y-46573D01*
X290243Y-46971D01*
X290945Y-47111D01*
X291647Y-46971D01*
X292243Y-46573D01*
X292640Y-45978D01*
X292780Y-45276D01*
X292640Y-44573D01*
X292243Y-43978D01*
X291647Y-43580D01*
X290945Y-43440D01*
D02*
G37*
G36*
X38382Y-46520D02*
X37680Y-46660D01*
X37084Y-47058D01*
X36686Y-47653D01*
X36547Y-48355D01*
X36641Y-48828D01*
X36191Y-49129D01*
X36135Y-49092D01*
X35433Y-48952D01*
X34731Y-49092D01*
X34135Y-49490D01*
X33737Y-50085D01*
X33598Y-50787D01*
X33737Y-51490D01*
X34135Y-52085D01*
X34731Y-52483D01*
X35433Y-52623D01*
X36135Y-52483D01*
X36657Y-52135D01*
X36731Y-52085D01*
X37083Y-52406D01*
X37051Y-52453D01*
X36917Y-52653D01*
X36778Y-53355D01*
X36917Y-54058D01*
X37315Y-54653D01*
X37911Y-55051D01*
X38613Y-55191D01*
X39315Y-55051D01*
X39911Y-54653D01*
X40308Y-54058D01*
X40448Y-53355D01*
X40308Y-52653D01*
X39911Y-52058D01*
X39315Y-51660D01*
X38613Y-51520D01*
X37911Y-51660D01*
X37389Y-52008D01*
X37315Y-52058D01*
X36963Y-51737D01*
X36995Y-51689D01*
X37129Y-51490D01*
X37268Y-50787D01*
X37174Y-50315D01*
X37624Y-50014D01*
X37680Y-50051D01*
X38382Y-50191D01*
X39084Y-50051D01*
X39680Y-49653D01*
X40077Y-49058D01*
X40217Y-48355D01*
X40077Y-47653D01*
X39680Y-47058D01*
X39084Y-46660D01*
X38382Y-46520D01*
D02*
G37*
G36*
X616142Y-45803D02*
X615439Y-45942D01*
X614844Y-46340D01*
X614446Y-46935D01*
X614306Y-47638D01*
X614446Y-48340D01*
X614844Y-48935D01*
X615439Y-49333D01*
X616142Y-49473D01*
X616844Y-49333D01*
X617440Y-48935D01*
X617837Y-48340D01*
X617977Y-47638D01*
X617837Y-46935D01*
X617440Y-46340D01*
X616844Y-45942D01*
X616142Y-45803D01*
D02*
G37*
G36*
X613386Y-48952D02*
X612683Y-49092D01*
X612088Y-49490D01*
X611690Y-50085D01*
X611663Y-50223D01*
X611134Y-50317D01*
X610845Y-49883D01*
X610250Y-49485D01*
X609547Y-49346D01*
X608845Y-49485D01*
X608252Y-49882D01*
X607991Y-49490D01*
X607395Y-49092D01*
X606693Y-48952D01*
X605991Y-49092D01*
X605395Y-49490D01*
X604997Y-50085D01*
X604858Y-50787D01*
X604997Y-51490D01*
X605395Y-52085D01*
X605991Y-52483D01*
X606693Y-52623D01*
X607395Y-52483D01*
X607988Y-52087D01*
X608250Y-52479D01*
X608845Y-52877D01*
X609547Y-53016D01*
X610250Y-52877D01*
X610845Y-52479D01*
X611243Y-51883D01*
X611270Y-51746D01*
X611799Y-51652D01*
X612088Y-52085D01*
X612683Y-52483D01*
X613386Y-52623D01*
X614088Y-52483D01*
X614684Y-52085D01*
X615081Y-51490D01*
X615221Y-50787D01*
X615081Y-50085D01*
X614684Y-49490D01*
X614088Y-49092D01*
X613386Y-48952D01*
D02*
G37*
G36*
X599213Y-48165D02*
X598510Y-48304D01*
X597915Y-48702D01*
X597517Y-49298D01*
X597377Y-50000D01*
X597517Y-50702D01*
X597915Y-51298D01*
X598510Y-51696D01*
X599213Y-51835D01*
X599915Y-51696D01*
X600510Y-51298D01*
X600908Y-50702D01*
X601048Y-50000D01*
X600908Y-49298D01*
X600510Y-48702D01*
X599915Y-48304D01*
X599213Y-48165D01*
D02*
G37*
G36*
X618898Y-48952D02*
X618195Y-49092D01*
X617600Y-49490D01*
X617202Y-50085D01*
X617062Y-50787D01*
X617202Y-51490D01*
X617600Y-52085D01*
X618195Y-52483D01*
X618898Y-52623D01*
X619600Y-52483D01*
X620195Y-52085D01*
X620593Y-51490D01*
X620733Y-50787D01*
X620593Y-50085D01*
X620195Y-49490D01*
X619600Y-49092D01*
X618898Y-48952D01*
D02*
G37*
G36*
X534646Y-40291D02*
X533943Y-40430D01*
X533348Y-40828D01*
X532950Y-41424D01*
X532810Y-42126D01*
X532950Y-42828D01*
X533348Y-43424D01*
X533389Y-43451D01*
Y-43951D01*
X533348Y-43978D01*
X532950Y-44573D01*
X532810Y-45276D01*
X532950Y-45978D01*
X533226Y-46391D01*
X533348Y-46573D01*
X533116Y-47019D01*
X532954Y-47128D01*
X532556Y-47723D01*
X532417Y-48425D01*
X532556Y-49128D01*
X532954Y-49723D01*
X533410Y-50028D01*
X533472Y-50480D01*
X533445Y-50606D01*
X533348Y-50671D01*
X532950Y-51266D01*
X532810Y-51968D01*
X532950Y-52671D01*
X533348Y-53266D01*
X533943Y-53664D01*
X534646Y-53804D01*
X535348Y-53664D01*
X535943Y-53266D01*
X536341Y-52671D01*
X536481Y-51968D01*
X536341Y-51266D01*
X535943Y-50671D01*
X535487Y-50366D01*
X535426Y-49914D01*
X535453Y-49788D01*
X535550Y-49723D01*
X535948Y-49128D01*
X536087Y-48425D01*
X535948Y-47723D01*
X535672Y-47310D01*
X535550Y-47128D01*
X535782Y-46681D01*
X535943Y-46573D01*
X536341Y-45978D01*
X536481Y-45276D01*
X536341Y-44573D01*
X535943Y-43978D01*
X535903Y-43951D01*
Y-43451D01*
X535943Y-43424D01*
X536341Y-42828D01*
X536481Y-42126D01*
X536341Y-41424D01*
X535943Y-40828D01*
X535348Y-40430D01*
X534646Y-40291D01*
D02*
G37*
G36*
X121653Y-50921D02*
X120951Y-51060D01*
X120356Y-51458D01*
X119958Y-52054D01*
X119818Y-52756D01*
X119958Y-53458D01*
X120356Y-54054D01*
X120951Y-54452D01*
X121653Y-54591D01*
X122356Y-54452D01*
X122951Y-54054D01*
X123349Y-53458D01*
X123489Y-52756D01*
X123349Y-52054D01*
X122951Y-51458D01*
X122356Y-51060D01*
X121653Y-50921D01*
D02*
G37*
G36*
X210630Y-51314D02*
X209928Y-51454D01*
X209332Y-51852D01*
X208934Y-52447D01*
X208795Y-53150D01*
X208934Y-53852D01*
X209332Y-54447D01*
X209928Y-54845D01*
X210630Y-54985D01*
X211332Y-54845D01*
X211928Y-54447D01*
X212326Y-53852D01*
X212465Y-53150D01*
X212326Y-52447D01*
X211928Y-51852D01*
X211332Y-51454D01*
X210630Y-51314D01*
D02*
G37*
G36*
X601575Y-51708D02*
X600873Y-51848D01*
X600277Y-52246D01*
X599879Y-52841D01*
X599740Y-53543D01*
X599879Y-54246D01*
X600277Y-54841D01*
X600873Y-55239D01*
X601575Y-55379D01*
X602277Y-55239D01*
X602873Y-54841D01*
X603270Y-54246D01*
X603410Y-53543D01*
X603270Y-52841D01*
X602873Y-52246D01*
X602277Y-51848D01*
X601575Y-51708D01*
D02*
G37*
G36*
X138297Y-51047D02*
X137323Y-51241D01*
X136498Y-51793D01*
X135946Y-52618D01*
X135752Y-53592D01*
X135946Y-54566D01*
X136498Y-55392D01*
X137323Y-55943D01*
X138297Y-56137D01*
X139271Y-55943D01*
X140097Y-55392D01*
X140648Y-54566D01*
X140842Y-53592D01*
X140648Y-52618D01*
X140097Y-51793D01*
X139271Y-51241D01*
X138297Y-51047D01*
D02*
G37*
G36*
X152756Y-55645D02*
X152054Y-55785D01*
X151458Y-56183D01*
X151060Y-56778D01*
X150921Y-57480D01*
X151060Y-58183D01*
X151458Y-58778D01*
X152054Y-59176D01*
X152756Y-59316D01*
X153458Y-59176D01*
X154054Y-58778D01*
X154452Y-58183D01*
X154591Y-57480D01*
X154452Y-56778D01*
X154054Y-56183D01*
X153458Y-55785D01*
X152756Y-55645D01*
D02*
G37*
G36*
X121457Y-55694D02*
X120754Y-55834D01*
X120159Y-56231D01*
X119761Y-56827D01*
X119622Y-57529D01*
X119761Y-58232D01*
X120159Y-58827D01*
X120754Y-59225D01*
X121457Y-59364D01*
X122159Y-59225D01*
X122754Y-58827D01*
X123152Y-58232D01*
X123292Y-57529D01*
X123152Y-56827D01*
X122754Y-56231D01*
X122159Y-55834D01*
X121457Y-55694D01*
D02*
G37*
G36*
X38583Y-56520D02*
X37880Y-56660D01*
X37285Y-57058D01*
X36887Y-57653D01*
X36747Y-58355D01*
X36887Y-59058D01*
X37285Y-59653D01*
X37880Y-60051D01*
X38583Y-60191D01*
X39285Y-60051D01*
X39880Y-59653D01*
X40278Y-59058D01*
X40418Y-58355D01*
X40278Y-57653D01*
X39880Y-57058D01*
X39285Y-56660D01*
X38583Y-56520D01*
D02*
G37*
G36*
X209541Y-56854D02*
X208839Y-56994D01*
X208244Y-57391D01*
X207846Y-57987D01*
X207706Y-58689D01*
X207846Y-59391D01*
X208244Y-59987D01*
X208839Y-60385D01*
X209541Y-60524D01*
X210244Y-60385D01*
X210839Y-59987D01*
X211237Y-59391D01*
X211377Y-58689D01*
X211237Y-57987D01*
X210839Y-57391D01*
X210244Y-56994D01*
X209541Y-56854D01*
D02*
G37*
G36*
X618110Y-60369D02*
X617408Y-60509D01*
X616813Y-60907D01*
X616415Y-61502D01*
X616275Y-62205D01*
X616415Y-62907D01*
X616813Y-63502D01*
X617408Y-63900D01*
X618110Y-64040D01*
X618813Y-63900D01*
X619408Y-63502D01*
X619806Y-62907D01*
X619945Y-62205D01*
X619806Y-61502D01*
X619408Y-60907D01*
X618813Y-60509D01*
X618110Y-60369D01*
D02*
G37*
G36*
X66102Y-62249D02*
X65400Y-62389D01*
X64805Y-62787D01*
X64407Y-63382D01*
X64267Y-64085D01*
X64407Y-64787D01*
X64805Y-65382D01*
X65400Y-65780D01*
X66102Y-65920D01*
X66805Y-65780D01*
X67400Y-65382D01*
X67798Y-64787D01*
X67938Y-64085D01*
X67798Y-63382D01*
X67400Y-62787D01*
X66805Y-62389D01*
X66102Y-62249D01*
D02*
G37*
G36*
X152756Y-63519D02*
X152054Y-63659D01*
X151458Y-64057D01*
X151060Y-64652D01*
X150921Y-65354D01*
X151060Y-66057D01*
X151458Y-66652D01*
X152054Y-67050D01*
X152756Y-67190D01*
X153458Y-67050D01*
X154054Y-66652D01*
X154452Y-66057D01*
X154591Y-65354D01*
X154452Y-64652D01*
X154054Y-64057D01*
X153458Y-63659D01*
X152756Y-63519D01*
D02*
G37*
G36*
X117323D02*
X116621Y-63659D01*
X116025Y-64057D01*
X115627Y-64652D01*
X115488Y-65354D01*
X115627Y-66057D01*
X116025Y-66652D01*
X116621Y-67050D01*
X117323Y-67190D01*
X118025Y-67050D01*
X118621Y-66652D01*
X119018Y-66057D01*
X119158Y-65354D01*
X119018Y-64652D01*
X118621Y-64057D01*
X118025Y-63659D01*
X117323Y-63519D01*
D02*
G37*
G36*
X-23622Y-58204D02*
X-24324Y-58344D01*
X-24920Y-58742D01*
X-25318Y-59337D01*
X-25457Y-60039D01*
X-25318Y-60742D01*
X-25032Y-61168D01*
X-24958Y-61516D01*
X-25032Y-61863D01*
X-25318Y-62290D01*
X-25457Y-62992D01*
X-25318Y-63694D01*
X-24920Y-64290D01*
X-24324Y-64688D01*
X-24234Y-64706D01*
Y-65215D01*
X-24324Y-65234D01*
X-24920Y-65631D01*
X-25318Y-66227D01*
X-25457Y-66929D01*
X-25318Y-67631D01*
X-24920Y-68227D01*
X-24324Y-68625D01*
X-23622Y-68764D01*
X-22920Y-68625D01*
X-22324Y-68227D01*
X-21926Y-67631D01*
X-21787Y-66929D01*
X-21926Y-66227D01*
X-22324Y-65631D01*
X-22920Y-65234D01*
X-23010Y-65215D01*
Y-64706D01*
X-22920Y-64688D01*
X-22324Y-64290D01*
X-21926Y-63694D01*
X-21787Y-62992D01*
X-21926Y-62290D01*
X-22212Y-61863D01*
X-22286Y-61516D01*
X-22212Y-61168D01*
X-21926Y-60742D01*
X-21787Y-60039D01*
X-21926Y-59337D01*
X-22324Y-58742D01*
X-22920Y-58344D01*
X-23622Y-58204D01*
D02*
G37*
G36*
X326772Y-67456D02*
X326069Y-67596D01*
X325474Y-67994D01*
X325076Y-68589D01*
X324936Y-69291D01*
X325076Y-69994D01*
X325474Y-70589D01*
X326069Y-70987D01*
X326772Y-71127D01*
X327474Y-70987D01*
X328069Y-70589D01*
X328467Y-69994D01*
X328607Y-69291D01*
X328467Y-68589D01*
X328069Y-67994D01*
X327474Y-67596D01*
X326772Y-67456D01*
D02*
G37*
G36*
X322441D02*
X321739Y-67596D01*
X321143Y-67994D01*
X320745Y-68589D01*
X320606Y-69291D01*
X320745Y-69994D01*
X321143Y-70589D01*
X321739Y-70987D01*
X322441Y-71127D01*
X323143Y-70987D01*
X323739Y-70589D01*
X324136Y-69994D01*
X324276Y-69291D01*
X324136Y-68589D01*
X323739Y-67994D01*
X323143Y-67596D01*
X322441Y-67456D01*
D02*
G37*
G36*
X138297Y-66795D02*
X137323Y-66989D01*
X136498Y-67541D01*
X135946Y-68366D01*
X135752Y-69340D01*
X135946Y-70314D01*
X136498Y-71140D01*
X137323Y-71691D01*
X138297Y-71885D01*
X139271Y-71691D01*
X140097Y-71140D01*
X140648Y-70314D01*
X140842Y-69340D01*
X140648Y-68366D01*
X140097Y-67541D01*
X139271Y-66989D01*
X138297Y-66795D01*
D02*
G37*
G36*
X246063Y-68243D02*
X245361Y-68383D01*
X244765Y-68781D01*
X244367Y-69376D01*
X244228Y-70079D01*
X244367Y-70781D01*
X244765Y-71377D01*
X245312Y-71742D01*
X245327Y-71934D01*
X245259Y-72262D01*
X244967Y-72320D01*
X244372Y-72718D01*
X243974Y-73313D01*
X243956Y-73404D01*
X243446D01*
X243428Y-73313D01*
X243030Y-72718D01*
X242435Y-72320D01*
X242344Y-72302D01*
Y-71792D01*
X242435Y-71774D01*
X243030Y-71377D01*
X243428Y-70781D01*
X243567Y-70079D01*
X243428Y-69376D01*
X243030Y-68781D01*
X242435Y-68383D01*
X241732Y-68243D01*
X241030Y-68383D01*
X240435Y-68781D01*
X240037Y-69376D01*
X239897Y-70079D01*
X240037Y-70781D01*
X240435Y-71377D01*
X241030Y-71774D01*
X241121Y-71792D01*
Y-72302D01*
X241030Y-72320D01*
X240435Y-72718D01*
X240037Y-73313D01*
X239897Y-74016D01*
X240037Y-74718D01*
X240435Y-75314D01*
X241030Y-75711D01*
X241732Y-75851D01*
X242435Y-75711D01*
X243030Y-75314D01*
X243428Y-74718D01*
X243446Y-74627D01*
X243956D01*
X243974Y-74718D01*
X244372Y-75314D01*
X244967Y-75711D01*
X245669Y-75851D01*
X246372Y-75711D01*
X246967Y-75314D01*
X247365Y-74718D01*
X247505Y-74016D01*
X247365Y-73313D01*
X246967Y-72718D01*
X246420Y-72353D01*
X246405Y-72160D01*
X246473Y-71832D01*
X246765Y-71774D01*
X247361Y-71377D01*
X247759Y-70781D01*
X247898Y-70079D01*
X247759Y-69376D01*
X247361Y-68781D01*
X246765Y-68383D01*
X246063Y-68243D01*
D02*
G37*
G36*
X317717Y-67456D02*
X317014Y-67596D01*
X316419Y-67994D01*
X316021Y-68589D01*
X315881Y-69291D01*
X316021Y-69994D01*
X316419Y-70589D01*
X317014Y-70987D01*
X317105Y-71005D01*
Y-71515D01*
X317014Y-71533D01*
X316419Y-71931D01*
X316021Y-72526D01*
X315881Y-73228D01*
X316021Y-73931D01*
X316419Y-74526D01*
X317014Y-74924D01*
X317717Y-75064D01*
X318419Y-74924D01*
X319014Y-74526D01*
X319412Y-73931D01*
X319552Y-73228D01*
X319412Y-72526D01*
X319014Y-71931D01*
X318419Y-71533D01*
X318328Y-71515D01*
Y-71005D01*
X318419Y-70987D01*
X319014Y-70589D01*
X319412Y-69994D01*
X319552Y-69291D01*
X319412Y-68589D01*
X319014Y-67994D01*
X318419Y-67596D01*
X317717Y-67456D01*
D02*
G37*
G36*
X157480Y-71393D02*
X156778Y-71533D01*
X156183Y-71931D01*
X155785Y-72526D01*
X155645Y-73228D01*
X155785Y-73931D01*
X156183Y-74526D01*
X156778Y-74924D01*
X157480Y-75064D01*
X158183Y-74924D01*
X158778Y-74526D01*
X159176Y-73931D01*
X159316Y-73228D01*
X159176Y-72526D01*
X158778Y-71931D01*
X158183Y-71533D01*
X157480Y-71393D01*
D02*
G37*
G36*
X326772Y-71787D02*
X326069Y-71926D01*
X325474Y-72324D01*
X325076Y-72920D01*
X324936Y-73622D01*
X325076Y-74324D01*
X325474Y-74920D01*
X326069Y-75318D01*
X326772Y-75457D01*
X327474Y-75318D01*
X328069Y-74920D01*
X328467Y-74324D01*
X328607Y-73622D01*
X328467Y-72920D01*
X328069Y-72324D01*
X327474Y-71926D01*
X326772Y-71787D01*
D02*
G37*
G36*
X322441D02*
X321739Y-71926D01*
X321143Y-72324D01*
X320745Y-72920D01*
X320606Y-73622D01*
X320745Y-74324D01*
X321143Y-74920D01*
X321739Y-75318D01*
X322441Y-75457D01*
X323143Y-75318D01*
X323739Y-74920D01*
X324136Y-74324D01*
X324276Y-73622D01*
X324136Y-72920D01*
X323739Y-72324D01*
X323143Y-71926D01*
X322441Y-71787D01*
D02*
G37*
G36*
X209449Y-70212D02*
X208747Y-70352D01*
X208151Y-70749D01*
X207753Y-71345D01*
X207614Y-72047D01*
X207753Y-72750D01*
X208073Y-73228D01*
X207753Y-73707D01*
X207614Y-74410D01*
X207753Y-75112D01*
X208151Y-75707D01*
X208747Y-76105D01*
X209449Y-76245D01*
X210151Y-76105D01*
X210747Y-75707D01*
X211144Y-75112D01*
X211284Y-74410D01*
X211144Y-73707D01*
X210824Y-73228D01*
X211144Y-72750D01*
X211284Y-72047D01*
X211144Y-71345D01*
X210747Y-70749D01*
X210151Y-70352D01*
X209449Y-70212D01*
D02*
G37*
G36*
X121467Y-72739D02*
X120764Y-72879D01*
X120169Y-73277D01*
X119771Y-73872D01*
X119631Y-74575D01*
X119771Y-75277D01*
X120169Y-75872D01*
X120764Y-76270D01*
X121467Y-76410D01*
X122169Y-76270D01*
X122764Y-75872D01*
X123162Y-75277D01*
X123302Y-74575D01*
X123162Y-73872D01*
X122764Y-73277D01*
X122169Y-72879D01*
X121467Y-72739D01*
D02*
G37*
G36*
X462992Y-74543D02*
X462290Y-74682D01*
X461694Y-75080D01*
X461297Y-75676D01*
X461157Y-76378D01*
X461297Y-77080D01*
X461694Y-77676D01*
X462290Y-78074D01*
X462992Y-78213D01*
X463694Y-78074D01*
X464290Y-77676D01*
X464688Y-77080D01*
X464827Y-76378D01*
X464688Y-75676D01*
X464290Y-75080D01*
X463694Y-74682D01*
X462992Y-74543D01*
D02*
G37*
G36*
X85039Y-75724D02*
X84337Y-75863D01*
X83742Y-76261D01*
X83344Y-76857D01*
X83204Y-77559D01*
X83344Y-78261D01*
X83742Y-78857D01*
X84337Y-79255D01*
X85039Y-79394D01*
X85742Y-79255D01*
X86337Y-78857D01*
X86735Y-78261D01*
X86875Y-77559D01*
X86735Y-76857D01*
X86337Y-76261D01*
X85742Y-75863D01*
X85039Y-75724D01*
D02*
G37*
G36*
X194882Y-75154D02*
X194056Y-75263D01*
X193286Y-75582D01*
X192624Y-76089D01*
X192117Y-76750D01*
X191798Y-77520D01*
X191689Y-78347D01*
X191798Y-79173D01*
X192117Y-79943D01*
X192624Y-80604D01*
X193286Y-81111D01*
X194056Y-81430D01*
X194882Y-81539D01*
X195708Y-81430D01*
X196478Y-81111D01*
X197139Y-80604D01*
X197647Y-79943D01*
X197966Y-79173D01*
X198074Y-78347D01*
X197966Y-77520D01*
X197647Y-76750D01*
X197139Y-76089D01*
X196478Y-75582D01*
X195708Y-75263D01*
X194882Y-75154D01*
D02*
G37*
G36*
X149606Y-78480D02*
X148904Y-78619D01*
X148309Y-79017D01*
X147911Y-79613D01*
X147771Y-80315D01*
X147911Y-81017D01*
X148309Y-81613D01*
X148904Y-82011D01*
X149606Y-82150D01*
X150309Y-82011D01*
X150904Y-81613D01*
X151302Y-81017D01*
X151442Y-80315D01*
X151302Y-79613D01*
X150904Y-79017D01*
X150309Y-78619D01*
X149606Y-78480D01*
D02*
G37*
G36*
X608268Y-82417D02*
X607565Y-82556D01*
X606970Y-82954D01*
X606572Y-83550D01*
X606432Y-84252D01*
X606572Y-84954D01*
X606970Y-85550D01*
X607565Y-85948D01*
X608268Y-86087D01*
X608970Y-85948D01*
X609565Y-85550D01*
X609963Y-84954D01*
X610103Y-84252D01*
X609963Y-83550D01*
X609565Y-82954D01*
X608970Y-82556D01*
X608268Y-82417D01*
D02*
G37*
G36*
X180610Y-85960D02*
X179908Y-86100D01*
X179413Y-86430D01*
X179085Y-86470D01*
X178756Y-86430D01*
X178261Y-86100D01*
X177559Y-85960D01*
X176857Y-86100D01*
X176261Y-86498D01*
X175864Y-87093D01*
X175724Y-87795D01*
X175864Y-88498D01*
X176261Y-89093D01*
X176857Y-89491D01*
X177559Y-89631D01*
X178261Y-89491D01*
X178756Y-89160D01*
X179085Y-89121D01*
X179413Y-89160D01*
X179908Y-89491D01*
X180610Y-89631D01*
X181313Y-89491D01*
X181908Y-89093D01*
X182306Y-88498D01*
X182446Y-87795D01*
X182306Y-87093D01*
X181908Y-86498D01*
X181313Y-86100D01*
X180610Y-85960D01*
D02*
G37*
G36*
X603543D02*
X602841Y-86100D01*
X602246Y-86498D01*
X601848Y-87093D01*
X601708Y-87795D01*
X601848Y-88498D01*
X602246Y-89093D01*
X602841Y-89491D01*
X603543Y-89631D01*
X604246Y-89491D01*
X604841Y-89093D01*
X605239Y-88498D01*
X605379Y-87795D01*
X605239Y-87093D01*
X604841Y-86498D01*
X604246Y-86100D01*
X603543Y-85960D01*
D02*
G37*
G36*
X198524D02*
X197821Y-86100D01*
X197226Y-86498D01*
X196828Y-87093D01*
X196688Y-87795D01*
X196828Y-88498D01*
X197226Y-89093D01*
X197821Y-89491D01*
X198524Y-89631D01*
X199226Y-89491D01*
X199821Y-89093D01*
X200219Y-88498D01*
X200359Y-87795D01*
X200219Y-87093D01*
X199821Y-86498D01*
X199226Y-86100D01*
X198524Y-85960D01*
D02*
G37*
G36*
X189764Y-86354D02*
X189061Y-86493D01*
X188466Y-86891D01*
X188068Y-87487D01*
X187928Y-88189D01*
X188068Y-88891D01*
X188466Y-89487D01*
X189061Y-89885D01*
X189764Y-90024D01*
X190466Y-89885D01*
X191061Y-89487D01*
X191459Y-88891D01*
X191599Y-88189D01*
X191459Y-87487D01*
X191061Y-86891D01*
X190466Y-86493D01*
X189764Y-86354D01*
D02*
G37*
G36*
X598397Y-86452D02*
X597694Y-86592D01*
X597099Y-86990D01*
X596701Y-87585D01*
X596561Y-88288D01*
X596701Y-88990D01*
X597099Y-89585D01*
X597694Y-89983D01*
X598397Y-90123D01*
X599099Y-89983D01*
X599694Y-89585D01*
X600092Y-88990D01*
X600232Y-88288D01*
X600092Y-87585D01*
X599694Y-86990D01*
X599099Y-86592D01*
X598397Y-86452D01*
D02*
G37*
G36*
X613406Y-87659D02*
X612703Y-87799D01*
X612108Y-88197D01*
X611710Y-88792D01*
X611570Y-89494D01*
X611710Y-90197D01*
X612108Y-90792D01*
X612703Y-91190D01*
X613406Y-91330D01*
X614108Y-91190D01*
X614703Y-90792D01*
X615101Y-90197D01*
X615241Y-89494D01*
X615101Y-88792D01*
X614703Y-88197D01*
X614108Y-87799D01*
X613406Y-87659D01*
D02*
G37*
G36*
X182283Y-95409D02*
X181581Y-95548D01*
X180986Y-95946D01*
X180588Y-96542D01*
X180448Y-97244D01*
X180588Y-97946D01*
X180986Y-98542D01*
X181581Y-98940D01*
X182283Y-99079D01*
X182986Y-98940D01*
X183581Y-98542D01*
X183979Y-97946D01*
X184119Y-97244D01*
X183979Y-96542D01*
X183581Y-95946D01*
X182986Y-95548D01*
X182283Y-95409D01*
D02*
G37*
G36*
X197638Y-95802D02*
X196935Y-95942D01*
X196340Y-96340D01*
X195942Y-96935D01*
X195802Y-97638D01*
X195942Y-98340D01*
X196340Y-98936D01*
X196935Y-99333D01*
X197638Y-99473D01*
X198340Y-99333D01*
X198935Y-98936D01*
X199333Y-98340D01*
X199473Y-97638D01*
X199333Y-96935D01*
X198935Y-96340D01*
X198340Y-95942D01*
X197638Y-95802D01*
D02*
G37*
G36*
X222351Y-96858D02*
X221649Y-96998D01*
X221053Y-97396D01*
X220655Y-97991D01*
X220516Y-98694D01*
X220655Y-99396D01*
X221053Y-99991D01*
X221649Y-100389D01*
X222351Y-100529D01*
X223053Y-100389D01*
X223649Y-99991D01*
X224046Y-99396D01*
X224186Y-98694D01*
X224046Y-97991D01*
X223649Y-97396D01*
X223053Y-96998D01*
X222351Y-96858D01*
D02*
G37*
G36*
X602105Y-97274D02*
X601402Y-97414D01*
X600807Y-97812D01*
X600409Y-98407D01*
X600269Y-99109D01*
X600409Y-99812D01*
X600807Y-100407D01*
X601402Y-100805D01*
X602105Y-100944D01*
X602807Y-100805D01*
X603402Y-100407D01*
X603800Y-99812D01*
X603940Y-99109D01*
X603800Y-98407D01*
X603402Y-97812D01*
X602807Y-97414D01*
X602105Y-97274D01*
D02*
G37*
G36*
X153150Y-97855D02*
X152447Y-97995D01*
X151852Y-98393D01*
X151454Y-98988D01*
X151314Y-99691D01*
X151454Y-100393D01*
X151852Y-100988D01*
X152447Y-101386D01*
X153150Y-101526D01*
X153852Y-101386D01*
X154447Y-100988D01*
X154845Y-100393D01*
X154985Y-99691D01*
X154845Y-98988D01*
X154447Y-98393D01*
X153852Y-97995D01*
X153150Y-97855D01*
D02*
G37*
G36*
X168110Y-98296D02*
X167408Y-98436D01*
X166813Y-98834D01*
X166415Y-99429D01*
X166275Y-100132D01*
X166415Y-100834D01*
X166813Y-101429D01*
X167408Y-101827D01*
X168110Y-101967D01*
X168813Y-101827D01*
X169408Y-101429D01*
X169806Y-100834D01*
X169946Y-100132D01*
X169806Y-99429D01*
X169408Y-98834D01*
X168813Y-98436D01*
X168110Y-98296D01*
D02*
G37*
G36*
X613402Y-94236D02*
X605496D01*
Y-102142D01*
X613402D01*
Y-94236D01*
D02*
G37*
G36*
X619449Y-94202D02*
X618417Y-94338D01*
X617455Y-94736D01*
X616630Y-95370D01*
X615996Y-96196D01*
X615598Y-97157D01*
X615462Y-98189D01*
X615598Y-99221D01*
X615996Y-100182D01*
X616630Y-101008D01*
X617455Y-101642D01*
X618417Y-102040D01*
X619449Y-102176D01*
X620481Y-102040D01*
X621442Y-101642D01*
X622268Y-101008D01*
X622901Y-100182D01*
X623300Y-99221D01*
X623436Y-98189D01*
X623300Y-97157D01*
X622901Y-96196D01*
X622268Y-95370D01*
X621442Y-94736D01*
X620481Y-94338D01*
X619449Y-94202D01*
D02*
G37*
G36*
X181004Y-99346D02*
X180302Y-99485D01*
X179706Y-99883D01*
X179308Y-100479D01*
X179169Y-101181D01*
X179308Y-101883D01*
X179706Y-102479D01*
X180302Y-102877D01*
X181004Y-103016D01*
X181706Y-102877D01*
X182302Y-102479D01*
X182700Y-101883D01*
X182839Y-101181D01*
X182700Y-100479D01*
X182302Y-99883D01*
X181706Y-99485D01*
X181004Y-99346D01*
D02*
G37*
G36*
X204331Y-99739D02*
X203628Y-99879D01*
X203033Y-100277D01*
X202635Y-100873D01*
X202496Y-101575D01*
X202635Y-102277D01*
X203033Y-102873D01*
X203628Y-103270D01*
X204331Y-103410D01*
X205033Y-103270D01*
X205628Y-102873D01*
X206026Y-102277D01*
X206166Y-101575D01*
X206026Y-100873D01*
X205628Y-100277D01*
X205033Y-99879D01*
X204331Y-99739D01*
D02*
G37*
G36*
X418898Y-98165D02*
X418195Y-98304D01*
X417600Y-98702D01*
X417202Y-99298D01*
X417062Y-100000D01*
X417202Y-100702D01*
X417600Y-101298D01*
X418195Y-101696D01*
X418898Y-101835D01*
X419600Y-101696D01*
X419780Y-101575D01*
X420230Y-101876D01*
X420212Y-101969D01*
X420352Y-102671D01*
X420750Y-103266D01*
X421345Y-103664D01*
X422047Y-103804D01*
X422750Y-103664D01*
X423345Y-103266D01*
X423743Y-102671D01*
X423882Y-101969D01*
X423743Y-101266D01*
X423345Y-100671D01*
X422750Y-100273D01*
X422047Y-100133D01*
X421345Y-100273D01*
X421164Y-100394D01*
X420714Y-100093D01*
X420733Y-100000D01*
X420593Y-99298D01*
X420195Y-98702D01*
X419600Y-98304D01*
X418898Y-98165D01*
D02*
G37*
G36*
X582058Y-81850D02*
X580331Y-81986D01*
X578648Y-82390D01*
X577048Y-83052D01*
X575572Y-83957D01*
X574255Y-85082D01*
X573131Y-86398D01*
X572226Y-87875D01*
X571564Y-89474D01*
X571159Y-91158D01*
X571024Y-92884D01*
X571159Y-94610D01*
X571564Y-96293D01*
X572226Y-97893D01*
X573131Y-99370D01*
X574255Y-100686D01*
X575572Y-101811D01*
X577048Y-102715D01*
X578648Y-103378D01*
X580331Y-103782D01*
X582058Y-103918D01*
X583784Y-103782D01*
X585467Y-103378D01*
X587067Y-102715D01*
X588543Y-101811D01*
X589860Y-100686D01*
X590984Y-99370D01*
X591889Y-97893D01*
X592552Y-96293D01*
X592956Y-94610D01*
X593091Y-92884D01*
X592956Y-91158D01*
X592552Y-89474D01*
X591889Y-87875D01*
X590984Y-86398D01*
X589860Y-85082D01*
X588543Y-83957D01*
X587067Y-83052D01*
X585467Y-82390D01*
X583784Y-81986D01*
X582058Y-81850D01*
D02*
G37*
G36*
X479695D02*
X477969Y-81986D01*
X476286Y-82390D01*
X474686Y-83052D01*
X473210Y-83957D01*
X471893Y-85082D01*
X470769Y-86398D01*
X469864Y-87875D01*
X469201Y-89474D01*
X468797Y-91158D01*
X468661Y-92884D01*
X468797Y-94610D01*
X469201Y-96293D01*
X469864Y-97893D01*
X470769Y-99370D01*
X471893Y-100686D01*
X473210Y-101811D01*
X474686Y-102715D01*
X476286Y-103378D01*
X477969Y-103782D01*
X479695Y-103918D01*
X481421Y-103782D01*
X483105Y-103378D01*
X484705Y-102715D01*
X486181Y-101811D01*
X487498Y-100686D01*
X488622Y-99370D01*
X489527Y-97893D01*
X490189Y-96293D01*
X490593Y-94610D01*
X490729Y-92884D01*
X490593Y-91158D01*
X490189Y-89474D01*
X489527Y-87875D01*
X488622Y-86398D01*
X487498Y-85082D01*
X486181Y-83957D01*
X484705Y-83052D01*
X483105Y-82390D01*
X481421Y-81986D01*
X479695Y-81850D01*
D02*
G37*
G36*
X211648Y-101859D02*
X210946Y-101999D01*
X210350Y-102397D01*
X209953Y-102992D01*
X209813Y-103695D01*
X209953Y-104397D01*
X210350Y-104992D01*
X210946Y-105390D01*
X211648Y-105530D01*
X212351Y-105390D01*
X212946Y-104992D01*
X213344Y-104397D01*
X213484Y-103695D01*
X213344Y-102992D01*
X212946Y-102397D01*
X212351Y-101999D01*
X211648Y-101859D01*
D02*
G37*
G36*
X365581Y-83523D02*
X363855Y-83659D01*
X362171Y-84063D01*
X360571Y-84725D01*
X359095Y-85630D01*
X357779Y-86755D01*
X356654Y-88071D01*
X355749Y-89547D01*
X355087Y-91147D01*
X354683Y-92831D01*
X354547Y-94557D01*
X354683Y-96283D01*
X355087Y-97966D01*
X355749Y-99566D01*
X356654Y-101042D01*
X357779Y-102359D01*
X359095Y-103483D01*
X360571Y-104388D01*
X362171Y-105051D01*
X363855Y-105455D01*
X365581Y-105591D01*
X367307Y-105455D01*
X368990Y-105051D01*
X370590Y-104388D01*
X372066Y-103483D01*
X373383Y-102359D01*
X374507Y-101042D01*
X375412Y-99566D01*
X376075Y-97966D01*
X376479Y-96283D01*
X376615Y-94557D01*
X376479Y-92831D01*
X376075Y-91147D01*
X375412Y-89547D01*
X374507Y-88071D01*
X373383Y-86755D01*
X372066Y-85630D01*
X370590Y-84725D01*
X368990Y-84063D01*
X367307Y-83659D01*
X365581Y-83523D01*
D02*
G37*
G36*
X127392D02*
X125666Y-83659D01*
X123982Y-84063D01*
X122382Y-84725D01*
X120906Y-85630D01*
X119589Y-86755D01*
X118465Y-88071D01*
X117560Y-89547D01*
X116898Y-91147D01*
X116494Y-92831D01*
X116358Y-94557D01*
X116494Y-96283D01*
X116898Y-97966D01*
X117560Y-99566D01*
X118465Y-101042D01*
X119589Y-102359D01*
X120906Y-103483D01*
X122382Y-104388D01*
X123982Y-105051D01*
X125666Y-105455D01*
X127392Y-105591D01*
X129118Y-105455D01*
X130801Y-105051D01*
X132401Y-104388D01*
X133877Y-103483D01*
X135194Y-102359D01*
X136319Y-101042D01*
X137223Y-99566D01*
X137886Y-97966D01*
X138290Y-96283D01*
X138426Y-94557D01*
X138290Y-92831D01*
X137886Y-91147D01*
X137223Y-89547D01*
X136319Y-88071D01*
X135194Y-86755D01*
X133877Y-85630D01*
X132401Y-84725D01*
X130801Y-84063D01*
X129118Y-83659D01*
X127392Y-83523D01*
D02*
G37*
G36*
X197244Y-100921D02*
X196542Y-101060D01*
X195946Y-101458D01*
X195548Y-102054D01*
X195409Y-102756D01*
X195548Y-103458D01*
X195946Y-104054D01*
X196542Y-104452D01*
X197244Y-104591D01*
X197329Y-104574D01*
X197630Y-105024D01*
X197497Y-105223D01*
X197358Y-105925D01*
X197497Y-106627D01*
X197895Y-107223D01*
X198491Y-107621D01*
X199193Y-107760D01*
X199895Y-107621D01*
X200491Y-107223D01*
X200888Y-106627D01*
X201028Y-105925D01*
X200888Y-105223D01*
X200491Y-104627D01*
X199895Y-104229D01*
X199193Y-104090D01*
X199108Y-104107D01*
X198807Y-103657D01*
X198940Y-103458D01*
X199079Y-102756D01*
X198940Y-102054D01*
X198542Y-101458D01*
X197946Y-101060D01*
X197244Y-100921D01*
D02*
G37*
G36*
X238189Y-105251D02*
X237487Y-105391D01*
X236891Y-105789D01*
X236493Y-106384D01*
X236354Y-107087D01*
X236493Y-107789D01*
X236891Y-108384D01*
X237487Y-108782D01*
X238189Y-108922D01*
X238891Y-108782D01*
X239487Y-108384D01*
X239884Y-107789D01*
X240024Y-107087D01*
X239884Y-106384D01*
X239487Y-105789D01*
X238891Y-105391D01*
X238189Y-105251D01*
D02*
G37*
G36*
X233071D02*
X232369Y-105391D01*
X231773Y-105789D01*
X231375Y-106384D01*
X231236Y-107087D01*
X231375Y-107789D01*
X231773Y-108384D01*
X232369Y-108782D01*
X233071Y-108922D01*
X233773Y-108782D01*
X234369Y-108384D01*
X234766Y-107789D01*
X234906Y-107087D01*
X234766Y-106384D01*
X234369Y-105789D01*
X233773Y-105391D01*
X233071Y-105251D01*
D02*
G37*
G36*
X228346Y-105645D02*
X227644Y-105785D01*
X227049Y-106183D01*
X226651Y-106778D01*
X226511Y-107480D01*
X226651Y-108183D01*
X227049Y-108778D01*
X227644Y-109176D01*
X228346Y-109316D01*
X229049Y-109176D01*
X229644Y-108778D01*
X230042Y-108183D01*
X230182Y-107480D01*
X230042Y-106778D01*
X229644Y-106183D01*
X229049Y-105785D01*
X228346Y-105645D01*
D02*
G37*
G36*
X223228D02*
X222526Y-105785D01*
X221931Y-106183D01*
X221533Y-106778D01*
X221393Y-107480D01*
X221533Y-108183D01*
X221931Y-108778D01*
X222526Y-109176D01*
X223228Y-109316D01*
X223931Y-109176D01*
X224526Y-108778D01*
X224924Y-108183D01*
X225064Y-107480D01*
X224924Y-106778D01*
X224526Y-106183D01*
X223931Y-105785D01*
X223228Y-105645D01*
D02*
G37*
G36*
X88981Y-106226D02*
X88279Y-106366D01*
X87684Y-106763D01*
X87286Y-107359D01*
X87212Y-107730D01*
X87022Y-108112D01*
X86675Y-108255D01*
X86279Y-108334D01*
X85684Y-108732D01*
X85286Y-109327D01*
X85205Y-109735D01*
X84695D01*
X84614Y-109327D01*
X84216Y-108732D01*
X83621Y-108334D01*
X83251Y-108261D01*
X82817Y-108061D01*
X82677Y-107359D01*
X82279Y-106763D01*
X81684Y-106366D01*
X80981Y-106226D01*
X80279Y-106366D01*
X79684Y-106763D01*
X79286Y-107359D01*
X79210Y-107742D01*
X78918Y-108194D01*
X78216Y-108334D01*
X77621Y-108732D01*
X77223Y-109327D01*
X77083Y-110029D01*
X77223Y-110732D01*
X77621Y-111327D01*
X78216Y-111725D01*
X78918Y-111865D01*
X79621Y-111725D01*
X80216Y-111327D01*
X80614Y-110732D01*
X80664Y-110483D01*
X81173D01*
X81223Y-110732D01*
X81621Y-111327D01*
X82216Y-111725D01*
X82918Y-111865D01*
X83621Y-111725D01*
X84216Y-111327D01*
X84614Y-110732D01*
X84695Y-110325D01*
X85205D01*
X85286Y-110732D01*
X85684Y-111327D01*
X86279Y-111725D01*
X86981Y-111865D01*
X87684Y-111725D01*
X88279Y-111327D01*
X88677Y-110732D01*
X88755Y-110340D01*
X89265D01*
X89349Y-110763D01*
X89747Y-111359D01*
X90342Y-111757D01*
X91044Y-111896D01*
X91747Y-111757D01*
X92342Y-111359D01*
X92740Y-110763D01*
X92880Y-110061D01*
X92740Y-109359D01*
X92342Y-108763D01*
X91747Y-108365D01*
X91284Y-108273D01*
X90817Y-108061D01*
X90677Y-107359D01*
X90279Y-106763D01*
X89684Y-106366D01*
X88981Y-106226D01*
D02*
G37*
G36*
X597244Y-106826D02*
X596542Y-106966D01*
X595946Y-107364D01*
X595548Y-107959D01*
X595409Y-108661D01*
X595548Y-109364D01*
X595946Y-109959D01*
X596542Y-110357D01*
X597244Y-110497D01*
X597946Y-110357D01*
X598542Y-109959D01*
X598940Y-109364D01*
X599079Y-108661D01*
X598940Y-107959D01*
X598542Y-107364D01*
X597946Y-106966D01*
X597244Y-106826D01*
D02*
G37*
G36*
X-23622Y-100527D02*
X-24324Y-100667D01*
X-24920Y-101065D01*
X-25318Y-101660D01*
X-25457Y-102362D01*
X-25318Y-103065D01*
X-24920Y-103660D01*
X-24324Y-104058D01*
X-24234Y-104076D01*
Y-104586D01*
X-24324Y-104604D01*
X-24920Y-105001D01*
X-25318Y-105597D01*
X-25457Y-106299D01*
X-25318Y-107001D01*
X-24920Y-107597D01*
X-24324Y-107995D01*
X-24234Y-108013D01*
Y-108523D01*
X-24324Y-108541D01*
X-24920Y-108939D01*
X-25318Y-109534D01*
X-25457Y-110236D01*
X-25318Y-110939D01*
X-24920Y-111534D01*
X-24324Y-111932D01*
X-23622Y-112072D01*
X-22920Y-111932D01*
X-22324Y-111534D01*
X-21926Y-110939D01*
X-21787Y-110236D01*
X-21926Y-109534D01*
X-22324Y-108939D01*
X-22920Y-108541D01*
X-23010Y-108523D01*
Y-108013D01*
X-22920Y-107995D01*
X-22324Y-107597D01*
X-21926Y-107001D01*
X-21787Y-106299D01*
X-21926Y-105597D01*
X-22324Y-105001D01*
X-22920Y-104604D01*
X-23010Y-104586D01*
Y-104076D01*
X-22920Y-104058D01*
X-22324Y-103660D01*
X-21926Y-103065D01*
X-21787Y-102362D01*
X-21926Y-101660D01*
X-22324Y-101065D01*
X-22920Y-100667D01*
X-23622Y-100527D01*
D02*
G37*
G36*
X619449Y-104202D02*
X618417Y-104338D01*
X617455Y-104736D01*
X616630Y-105370D01*
X615996Y-106196D01*
X615598Y-107157D01*
X615462Y-108189D01*
X615598Y-109221D01*
X615996Y-110182D01*
X616630Y-111008D01*
X617455Y-111642D01*
X618417Y-112040D01*
X619449Y-112176D01*
X620481Y-112040D01*
X621442Y-111642D01*
X622268Y-111008D01*
X622901Y-110182D01*
X623300Y-109221D01*
X623436Y-108189D01*
X623300Y-107157D01*
X622901Y-106196D01*
X622268Y-105370D01*
X621442Y-104736D01*
X620481Y-104338D01*
X619449Y-104202D01*
D02*
G37*
G36*
X609449D02*
X608417Y-104338D01*
X607455Y-104736D01*
X606630Y-105370D01*
X605996Y-106196D01*
X605598Y-107157D01*
X605462Y-108189D01*
X605598Y-109221D01*
X605996Y-110182D01*
X606630Y-111008D01*
X607455Y-111642D01*
X608417Y-112040D01*
X609449Y-112176D01*
X610481Y-112040D01*
X611442Y-111642D01*
X612268Y-111008D01*
X612901Y-110182D01*
X613300Y-109221D01*
X613436Y-108189D01*
X613300Y-107157D01*
X612901Y-106196D01*
X612268Y-105370D01*
X611442Y-104736D01*
X610481Y-104338D01*
X609449Y-104202D01*
D02*
G37*
G36*
X44621Y-108792D02*
X43919Y-108932D01*
X43324Y-109330D01*
X42926Y-109925D01*
X42786Y-110628D01*
X42926Y-111330D01*
X43324Y-111925D01*
X43919Y-112323D01*
X44621Y-112463D01*
X45324Y-112323D01*
X45919Y-111925D01*
X46317Y-111330D01*
X46457Y-110628D01*
X46317Y-109925D01*
X45919Y-109330D01*
X45324Y-108932D01*
X44621Y-108792D01*
D02*
G37*
G36*
X160075Y-110566D02*
X159373Y-110706D01*
X158778Y-111104D01*
X158380Y-111699D01*
X158240Y-112402D01*
X158380Y-113104D01*
X158778Y-113699D01*
X159373Y-114097D01*
X160075Y-114237D01*
X160778Y-114097D01*
X161373Y-113699D01*
X161771Y-113104D01*
X161910Y-112402D01*
X161771Y-111699D01*
X161373Y-111104D01*
X160778Y-110706D01*
X160075Y-110566D01*
D02*
G37*
G36*
X321260Y-113125D02*
X320557Y-113265D01*
X319962Y-113663D01*
X319564Y-114258D01*
X319546Y-114349D01*
X319036D01*
X319018Y-114258D01*
X318621Y-113663D01*
X318025Y-113265D01*
X317323Y-113125D01*
X316620Y-113265D01*
X316025Y-113663D01*
X315627Y-114258D01*
X315488Y-114961D01*
X315627Y-115663D01*
X316025Y-116258D01*
X316620Y-116656D01*
X317323Y-116796D01*
X318025Y-116656D01*
X318621Y-116258D01*
X319018Y-115663D01*
X319036Y-115572D01*
X319546D01*
X319564Y-115663D01*
X319962Y-116258D01*
X320557Y-116656D01*
X321260Y-116796D01*
X321962Y-116656D01*
X322558Y-116258D01*
X322955Y-115663D01*
X323095Y-114961D01*
X322955Y-114258D01*
X322558Y-113663D01*
X321962Y-113265D01*
X321260Y-113125D01*
D02*
G37*
G36*
X153150Y-111551D02*
X152447Y-111690D01*
X151852Y-112088D01*
X151454Y-112683D01*
X151314Y-113386D01*
X151454Y-114088D01*
X151852Y-114683D01*
X152447Y-115081D01*
X153150Y-115221D01*
X153852Y-115081D01*
X154447Y-114683D01*
X154845Y-114088D01*
X154985Y-113386D01*
X154845Y-112683D01*
X154447Y-112088D01*
X153852Y-111690D01*
X153150Y-111551D01*
D02*
G37*
G36*
X188028Y-111747D02*
X187326Y-111887D01*
X186730Y-112285D01*
X186332Y-112880D01*
X186193Y-113583D01*
X186332Y-114285D01*
X186730Y-114880D01*
X187326Y-115278D01*
X188028Y-115418D01*
X188730Y-115278D01*
X189326Y-114880D01*
X189724Y-114285D01*
X189863Y-113583D01*
X189724Y-112880D01*
X189326Y-112285D01*
X188730Y-111887D01*
X188028Y-111747D01*
D02*
G37*
G36*
X164843Y-112204D02*
X164140Y-112344D01*
X163545Y-112742D01*
X163147Y-113337D01*
X163008Y-114040D01*
X163147Y-114742D01*
X163545Y-115337D01*
X164140Y-115735D01*
X164843Y-115875D01*
X165545Y-115735D01*
X166141Y-115337D01*
X166538Y-114742D01*
X166678Y-114040D01*
X166538Y-113337D01*
X166141Y-112742D01*
X165545Y-112344D01*
X164843Y-112204D01*
D02*
G37*
G36*
X369685Y-116275D02*
X368983Y-116415D01*
X368692Y-116609D01*
X368307Y-116777D01*
X367922Y-116609D01*
X367631Y-116415D01*
X366929Y-116275D01*
X366227Y-116415D01*
X365664Y-116791D01*
X365517Y-116853D01*
X365191D01*
X365045Y-116791D01*
X364482Y-116415D01*
X363779Y-116275D01*
X363077Y-116415D01*
X362482Y-116813D01*
X362084Y-117408D01*
X361944Y-118110D01*
X362084Y-118813D01*
X362278Y-119103D01*
X362447Y-119488D01*
X362278Y-119873D01*
X362084Y-120164D01*
X361944Y-120866D01*
X362084Y-121569D01*
X362482Y-122164D01*
Y-122324D01*
X362084Y-122920D01*
X361944Y-123622D01*
X362084Y-124324D01*
X362482Y-124920D01*
X363077Y-125318D01*
X363779Y-125457D01*
X364482Y-125318D01*
X365045Y-124942D01*
X365191Y-124879D01*
X365517D01*
X365664Y-124942D01*
X366227Y-125318D01*
X366929Y-125457D01*
X367631Y-125318D01*
X367922Y-125123D01*
X368307Y-124955D01*
X368692Y-125123D01*
X368983Y-125318D01*
X369685Y-125457D01*
X370387Y-125318D01*
X370983Y-124920D01*
X371381Y-124324D01*
X371520Y-123622D01*
X371381Y-122920D01*
X370983Y-122324D01*
Y-122164D01*
X371381Y-121569D01*
X371520Y-120866D01*
X371381Y-120164D01*
X371186Y-119873D01*
X371018Y-119488D01*
X371186Y-119103D01*
X371381Y-118813D01*
X371520Y-118110D01*
X371381Y-117408D01*
X370983Y-116813D01*
X370387Y-116415D01*
X369685Y-116275D01*
D02*
G37*
G36*
X245276Y-113913D02*
X244573Y-114052D01*
X243978Y-114450D01*
X243580Y-115046D01*
X243440Y-115748D01*
X243580Y-116450D01*
X243978Y-117046D01*
X244573Y-117444D01*
X245276Y-117583D01*
X245978Y-117444D01*
X246573Y-117046D01*
X246971Y-116450D01*
X247111Y-115748D01*
X246971Y-115046D01*
X246573Y-114450D01*
X245978Y-114052D01*
X245276Y-113913D01*
D02*
G37*
G36*
X592913Y-114700D02*
X592211Y-114840D01*
X591616Y-115238D01*
X591218Y-115833D01*
X591078Y-116535D01*
X591218Y-117238D01*
X591616Y-117833D01*
X592211Y-118231D01*
X592913Y-118371D01*
X593616Y-118231D01*
X594211Y-117833D01*
X594609Y-117238D01*
X594749Y-116535D01*
X594609Y-115833D01*
X594211Y-115238D01*
X593616Y-114840D01*
X592913Y-114700D01*
D02*
G37*
G36*
X173228Y-115488D02*
X172526Y-115627D01*
X171931Y-116025D01*
X171533Y-116621D01*
X171393Y-117323D01*
X171533Y-118025D01*
X171931Y-118621D01*
X172526Y-119018D01*
X173228Y-119158D01*
X173931Y-119018D01*
X174526Y-118621D01*
X174924Y-118025D01*
X175064Y-117323D01*
X174924Y-116621D01*
X174526Y-116025D01*
X173931Y-115627D01*
X173228Y-115488D01*
D02*
G37*
G36*
X298031Y-111426D02*
X296974Y-111565D01*
X295988Y-111973D01*
X295142Y-112622D01*
X294493Y-113469D01*
X294085Y-114454D01*
X293945Y-115512D01*
X294085Y-116569D01*
X294493Y-117555D01*
X295142Y-118401D01*
X295988Y-119051D01*
X296974Y-119459D01*
X298031Y-119598D01*
X299089Y-119459D01*
X300075Y-119051D01*
X300921Y-118401D01*
X301570Y-117555D01*
X301978Y-116569D01*
X302118Y-115512D01*
X301978Y-114454D01*
X301570Y-113469D01*
X300921Y-112622D01*
X300075Y-111973D01*
X299089Y-111565D01*
X298031Y-111426D01*
D02*
G37*
G36*
X140551Y-114700D02*
X139849Y-114840D01*
X139253Y-115238D01*
X138856Y-115833D01*
X138716Y-116535D01*
X138842Y-117167D01*
X138668Y-117202D01*
X138072Y-117600D01*
X137674Y-118195D01*
X137535Y-118898D01*
X137674Y-119600D01*
X138072Y-120195D01*
X138668Y-120593D01*
X139370Y-120733D01*
X140072Y-120593D01*
X140668Y-120195D01*
X141066Y-119600D01*
X141205Y-118898D01*
X141080Y-118266D01*
X141253Y-118231D01*
X141849Y-117833D01*
X142247Y-117238D01*
X142386Y-116535D01*
X142247Y-115833D01*
X141849Y-115238D01*
X141253Y-114840D01*
X140551Y-114700D01*
D02*
G37*
G36*
X52501Y-118037D02*
X51799Y-118176D01*
X51203Y-118574D01*
X50805Y-119170D01*
X50666Y-119872D01*
X50805Y-120574D01*
X51203Y-121170D01*
X51799Y-121568D01*
X52501Y-121707D01*
X53203Y-121568D01*
X53799Y-121170D01*
X54197Y-120574D01*
X54336Y-119872D01*
X54197Y-119170D01*
X53799Y-118574D01*
X53203Y-118176D01*
X52501Y-118037D01*
D02*
G37*
G36*
X619449Y-114202D02*
X618417Y-114338D01*
X617455Y-114736D01*
X616630Y-115370D01*
X615996Y-116196D01*
X615598Y-117157D01*
X615462Y-118189D01*
X615598Y-119221D01*
X615996Y-120182D01*
X616630Y-121008D01*
X617455Y-121642D01*
X618417Y-122040D01*
X619449Y-122176D01*
X620481Y-122040D01*
X621442Y-121642D01*
X622268Y-121008D01*
X622901Y-120182D01*
X623300Y-119221D01*
X623436Y-118189D01*
X623300Y-117157D01*
X622901Y-116196D01*
X622268Y-115370D01*
X621442Y-114736D01*
X620481Y-114338D01*
X619449Y-114202D01*
D02*
G37*
G36*
X609449D02*
X608417Y-114338D01*
X607455Y-114736D01*
X606630Y-115370D01*
X605996Y-116196D01*
X605598Y-117157D01*
X605462Y-118189D01*
X605598Y-119221D01*
X605996Y-120182D01*
X606630Y-121008D01*
X607455Y-121642D01*
X608417Y-122040D01*
X609449Y-122176D01*
X610481Y-122040D01*
X611442Y-121642D01*
X612268Y-121008D01*
X612901Y-120182D01*
X613300Y-119221D01*
X613436Y-118189D01*
X613300Y-117157D01*
X612901Y-116196D01*
X612268Y-115370D01*
X611442Y-114736D01*
X610481Y-114338D01*
X609449Y-114202D01*
D02*
G37*
G36*
X245325Y-119002D02*
X244623Y-119141D01*
X244027Y-119539D01*
X243629Y-120135D01*
X243490Y-120837D01*
X243629Y-121539D01*
X244027Y-122135D01*
X244623Y-122532D01*
X245325Y-122672D01*
X246027Y-122532D01*
X246623Y-122135D01*
X247020Y-121539D01*
X247160Y-120837D01*
X247020Y-120135D01*
X246623Y-119539D01*
X246027Y-119141D01*
X245325Y-119002D01*
D02*
G37*
G36*
X130245Y-119034D02*
X129542Y-119174D01*
X128947Y-119572D01*
X128549Y-120167D01*
X128409Y-120870D01*
X128549Y-121572D01*
X128947Y-122167D01*
X129542Y-122565D01*
X130245Y-122705D01*
X130947Y-122565D01*
X131542Y-122167D01*
X131940Y-121572D01*
X132080Y-120870D01*
X131940Y-120167D01*
X131542Y-119572D01*
X130947Y-119174D01*
X130245Y-119034D01*
D02*
G37*
G36*
X140116Y-122213D02*
X139414Y-122353D01*
X138818Y-122751D01*
X138421Y-123346D01*
X138281Y-124048D01*
X138421Y-124751D01*
X138818Y-125346D01*
X139414Y-125744D01*
X140116Y-125884D01*
X140819Y-125744D01*
X141414Y-125346D01*
X141812Y-124751D01*
X141951Y-124048D01*
X141812Y-123346D01*
X141414Y-122751D01*
X140819Y-122353D01*
X140116Y-122213D01*
D02*
G37*
G36*
X150233Y-118047D02*
X149530Y-118186D01*
X148935Y-118584D01*
X148537Y-119180D01*
X148398Y-119882D01*
X148537Y-120584D01*
X148935Y-121180D01*
X149530Y-121577D01*
X150233Y-121717D01*
X150935Y-121577D01*
X150956Y-121564D01*
X151413Y-121860D01*
X151530Y-122449D01*
X151769Y-122807D01*
X151607Y-122915D01*
X151209Y-123510D01*
X151069Y-124213D01*
X151209Y-124915D01*
X151607Y-125510D01*
X152202Y-125908D01*
X152904Y-126048D01*
X153607Y-125908D01*
X154202Y-125510D01*
X154600Y-124915D01*
X154739Y-124213D01*
X154600Y-123510D01*
X154361Y-123153D01*
X154523Y-123044D01*
X154921Y-122449D01*
X155061Y-121747D01*
X154921Y-121044D01*
X154523Y-120449D01*
X153928Y-120051D01*
X153225Y-119911D01*
X152523Y-120051D01*
X152503Y-120065D01*
X152046Y-119769D01*
X151928Y-119180D01*
X151531Y-118584D01*
X150935Y-118186D01*
X150233Y-118047D01*
D02*
G37*
G36*
X281496Y-122574D02*
X280794Y-122714D01*
X280198Y-123112D01*
X279801Y-123707D01*
X279661Y-124409D01*
X279801Y-125112D01*
X280198Y-125707D01*
X280794Y-126105D01*
X281496Y-126245D01*
X282198Y-126105D01*
X282794Y-125707D01*
X283192Y-125112D01*
X283331Y-124409D01*
X283192Y-123707D01*
X282794Y-123112D01*
X282198Y-122714D01*
X281496Y-122574D01*
D02*
G37*
G36*
X449606Y-119818D02*
X448904Y-119958D01*
X448309Y-120356D01*
X447911Y-120951D01*
X447771Y-121653D01*
X447911Y-122356D01*
X448309Y-122951D01*
X448349Y-122978D01*
Y-123478D01*
X448309Y-123505D01*
X447911Y-124101D01*
X447771Y-124803D01*
X447911Y-125505D01*
X448309Y-126101D01*
X448568Y-126274D01*
Y-126875D01*
X448309Y-127049D01*
X447911Y-127644D01*
X447893Y-127735D01*
X447383D01*
X447365Y-127644D01*
X446967Y-127049D01*
X446372Y-126651D01*
X445669Y-126511D01*
X444967Y-126651D01*
X444372Y-127049D01*
X443974Y-127644D01*
X443834Y-128347D01*
X443974Y-129049D01*
X444372Y-129644D01*
X444967Y-130042D01*
X445669Y-130182D01*
X446372Y-130042D01*
X446967Y-129644D01*
X447365Y-129049D01*
X447383Y-128958D01*
X447893D01*
X447911Y-129049D01*
X448309Y-129644D01*
X448904Y-130042D01*
X449606Y-130182D01*
X450309Y-130042D01*
X450904Y-129644D01*
X451302Y-129049D01*
X451442Y-128347D01*
X451302Y-127644D01*
X450904Y-127049D01*
X450645Y-126875D01*
Y-126274D01*
X450904Y-126101D01*
X451302Y-125505D01*
X451442Y-124803D01*
X451302Y-124101D01*
X450904Y-123505D01*
X450864Y-123478D01*
Y-122978D01*
X450904Y-122951D01*
X451302Y-122356D01*
X451442Y-121653D01*
X451302Y-120951D01*
X450904Y-120356D01*
X450309Y-119958D01*
X449606Y-119818D01*
D02*
G37*
G36*
X255906Y-124543D02*
X255203Y-124682D01*
X254608Y-125080D01*
X254210Y-125676D01*
X254070Y-126378D01*
X254210Y-127080D01*
X254608Y-127676D01*
X255203Y-128074D01*
X255906Y-128213D01*
X256608Y-128074D01*
X257203Y-127676D01*
X257601Y-127080D01*
X257741Y-126378D01*
X257601Y-125676D01*
X257203Y-125080D01*
X256608Y-124682D01*
X255906Y-124543D01*
D02*
G37*
G36*
X35433Y-127692D02*
X34731Y-127832D01*
X34135Y-128230D01*
X34108Y-128270D01*
X33608D01*
X33581Y-128230D01*
X32986Y-127832D01*
X32283Y-127692D01*
X31581Y-127832D01*
X30986Y-128230D01*
X30812Y-128489D01*
X30211D01*
X30038Y-128230D01*
X29443Y-127832D01*
X28740Y-127692D01*
X28038Y-127832D01*
X27442Y-128230D01*
X27045Y-128825D01*
X26905Y-129528D01*
X27045Y-130230D01*
X27442Y-130825D01*
X28038Y-131223D01*
X28740Y-131363D01*
X29443Y-131223D01*
X30038Y-130825D01*
X30211Y-130566D01*
X30812D01*
X30986Y-130825D01*
X31581Y-131223D01*
X32283Y-131363D01*
X32986Y-131223D01*
X33581Y-130825D01*
X33608Y-130785D01*
X34108D01*
X34135Y-130825D01*
X34731Y-131223D01*
X35433Y-131363D01*
X36135Y-131223D01*
X36731Y-130825D01*
X37129Y-130230D01*
X37268Y-129528D01*
X37129Y-128825D01*
X36731Y-128230D01*
X36135Y-127832D01*
X35433Y-127692D01*
D02*
G37*
G36*
X51287Y-125042D02*
X50585Y-125182D01*
X49989Y-125580D01*
X49591Y-126175D01*
X49452Y-126878D01*
X49591Y-127580D01*
X49989Y-128175D01*
X50585Y-128573D01*
X51287Y-128713D01*
X51989Y-128573D01*
X52585Y-128175D01*
X52983Y-127580D01*
X53122Y-126878D01*
X52983Y-126175D01*
X52585Y-125580D01*
X51989Y-125182D01*
X51287Y-125042D01*
D02*
G37*
G36*
X13386D02*
X12684Y-125182D01*
X12088Y-125580D01*
X11690Y-126175D01*
X11551Y-126878D01*
X11690Y-127580D01*
X12088Y-128175D01*
X12684Y-128573D01*
X13386Y-128713D01*
X14088Y-128573D01*
X14683Y-128175D01*
X15081Y-127580D01*
X15221Y-126878D01*
X15081Y-126175D01*
X14683Y-125580D01*
X14088Y-125182D01*
X13386Y-125042D01*
D02*
G37*
G36*
X400984Y-125267D02*
X400282Y-125406D01*
X399687Y-125804D01*
X399289Y-126400D01*
X399149Y-127102D01*
X399289Y-127804D01*
X399687Y-128400D01*
X400282Y-128798D01*
X400984Y-128937D01*
X401687Y-128798D01*
X402282Y-128400D01*
X402680Y-127804D01*
X402819Y-127102D01*
X402680Y-126400D01*
X402282Y-125804D01*
X401687Y-125406D01*
X400984Y-125267D01*
D02*
G37*
G36*
X298031Y-121426D02*
X296974Y-121565D01*
X295988Y-121973D01*
X295142Y-122623D01*
X294493Y-123469D01*
X294085Y-124454D01*
X293945Y-125512D01*
X294085Y-126569D01*
X294493Y-127555D01*
X295142Y-128401D01*
X295988Y-129051D01*
X296974Y-129459D01*
X298031Y-129598D01*
X299089Y-129459D01*
X300075Y-129051D01*
X300921Y-128401D01*
X301570Y-127555D01*
X301978Y-126569D01*
X302118Y-125512D01*
X301978Y-124454D01*
X301570Y-123469D01*
X300921Y-122623D01*
X300075Y-121973D01*
X299089Y-121565D01*
X298031Y-121426D01*
D02*
G37*
G36*
X321260Y-121484D02*
X320177Y-121626D01*
X319167Y-122045D01*
X318300Y-122710D01*
X317635Y-123577D01*
X317217Y-124586D01*
X317074Y-125669D01*
X317217Y-126752D01*
X317635Y-127762D01*
X318300Y-128629D01*
X319167Y-129294D01*
X320177Y-129712D01*
X321260Y-129855D01*
X322343Y-129712D01*
X323353Y-129294D01*
X324219Y-128629D01*
X324885Y-127762D01*
X325303Y-126752D01*
X325445Y-125669D01*
X325303Y-124586D01*
X324885Y-123577D01*
X324219Y-122710D01*
X323353Y-122045D01*
X322343Y-121626D01*
X321260Y-121484D01*
D02*
G37*
G36*
X286221Y-122968D02*
X285518Y-123108D01*
X284923Y-123505D01*
X284525Y-124101D01*
X284385Y-124803D01*
X284525Y-125505D01*
X284889Y-126050D01*
X284824Y-126245D01*
X284642Y-126512D01*
X283943Y-126651D01*
X283348Y-127049D01*
X282950Y-127644D01*
X282810Y-128347D01*
X282950Y-129049D01*
X283348Y-129644D01*
X283943Y-130042D01*
X284646Y-130182D01*
X285348Y-130042D01*
X285943Y-129644D01*
X286341Y-129049D01*
X286481Y-128347D01*
X286341Y-127644D01*
X285978Y-127100D01*
X286042Y-126904D01*
X286224Y-126638D01*
X286923Y-126499D01*
X287518Y-126101D01*
X287916Y-125505D01*
X288056Y-124803D01*
X287916Y-124101D01*
X287518Y-123505D01*
X286923Y-123108D01*
X286221Y-122968D01*
D02*
G37*
G36*
X388713Y-126896D02*
X388010Y-127036D01*
X387415Y-127433D01*
X387017Y-128029D01*
X386877Y-128731D01*
X387017Y-129433D01*
X387415Y-130029D01*
X388010Y-130427D01*
X388713Y-130566D01*
X389415Y-130427D01*
X390010Y-130029D01*
X390408Y-129433D01*
X390548Y-128731D01*
X390408Y-128029D01*
X390010Y-127433D01*
X389415Y-127036D01*
X388713Y-126896D01*
D02*
G37*
G36*
X276650Y-126975D02*
X275948Y-127115D01*
X275352Y-127513D01*
X274954Y-128108D01*
X274815Y-128810D01*
X274954Y-129513D01*
X275352Y-130108D01*
X275948Y-130506D01*
X276650Y-130646D01*
X277352Y-130506D01*
X277948Y-130108D01*
X278346Y-129513D01*
X278485Y-128810D01*
X278346Y-128108D01*
X277948Y-127513D01*
X277352Y-127115D01*
X276650Y-126975D01*
D02*
G37*
G36*
X415748Y-127774D02*
X415046Y-127913D01*
X414450Y-128311D01*
X414052Y-128907D01*
X413913Y-129609D01*
X414052Y-130311D01*
X414450Y-130907D01*
X415046Y-131304D01*
X415748Y-131444D01*
X416450Y-131304D01*
X417046Y-130907D01*
X417503D01*
X417600Y-131051D01*
X418195Y-131449D01*
X418898Y-131589D01*
X419600Y-131449D01*
X420195Y-131051D01*
X420593Y-130456D01*
X420733Y-129753D01*
X420593Y-129051D01*
X420195Y-128456D01*
X419600Y-128058D01*
X418898Y-127918D01*
X418195Y-128058D01*
X417600Y-128456D01*
X417142D01*
X417046Y-128311D01*
X416450Y-127913D01*
X415748Y-127774D01*
D02*
G37*
G36*
X98761Y-115911D02*
X98059Y-116051D01*
X97463Y-116448D01*
X97065Y-117044D01*
X96926Y-117746D01*
X97065Y-118448D01*
X97463Y-119044D01*
X98059Y-119442D01*
X98454Y-119520D01*
X98494Y-119552D01*
X98458Y-120088D01*
X98430Y-120102D01*
X98059Y-120176D01*
X97463Y-120574D01*
X97065Y-121169D01*
X96926Y-121871D01*
X97065Y-122574D01*
X97463Y-123169D01*
X98059Y-123567D01*
X98308Y-123617D01*
Y-124126D01*
X98059Y-124176D01*
X97463Y-124574D01*
X97065Y-125169D01*
X96926Y-125872D01*
X97065Y-126574D01*
X97463Y-127169D01*
X98059Y-127567D01*
X98309Y-127617D01*
Y-128127D01*
X98059Y-128176D01*
X97463Y-128574D01*
X97065Y-129170D01*
X96926Y-129872D01*
X97065Y-130574D01*
X97463Y-131170D01*
X98059Y-131568D01*
X98761Y-131707D01*
X99463Y-131568D01*
X100059Y-131170D01*
X100456Y-130574D01*
X100596Y-129872D01*
X101060Y-129641D01*
X101432Y-129567D01*
X102027Y-129169D01*
X102425Y-128574D01*
X102565Y-127872D01*
X102425Y-127169D01*
X102027Y-126574D01*
X101432Y-126176D01*
X101060Y-126102D01*
X100596Y-125872D01*
X100456Y-125169D01*
X100059Y-124574D01*
X99463Y-124176D01*
X99214Y-124126D01*
Y-123617D01*
X99463Y-123567D01*
X100059Y-123169D01*
X100456Y-122574D01*
X100596Y-121871D01*
X101060Y-121641D01*
X101432Y-121567D01*
X102027Y-121169D01*
X102425Y-120574D01*
X102565Y-119871D01*
X102425Y-119169D01*
X102027Y-118574D01*
X101432Y-118176D01*
X101036Y-118097D01*
X100596Y-117746D01*
X100456Y-117044D01*
X100059Y-116448D01*
X99463Y-116051D01*
X98761Y-115911D01*
D02*
G37*
G36*
X619449Y-124202D02*
X618417Y-124338D01*
X617455Y-124736D01*
X616630Y-125370D01*
X615996Y-126196D01*
X615598Y-127157D01*
X615462Y-128189D01*
X615598Y-129221D01*
X615996Y-130182D01*
X616630Y-131008D01*
X617455Y-131642D01*
X618417Y-132040D01*
X619449Y-132176D01*
X620481Y-132040D01*
X621442Y-131642D01*
X622268Y-131008D01*
X622901Y-130182D01*
X623300Y-129221D01*
X623436Y-128189D01*
X623300Y-127157D01*
X622901Y-126196D01*
X622268Y-125370D01*
X621442Y-124736D01*
X620481Y-124338D01*
X619449Y-124202D01*
D02*
G37*
G36*
X609449D02*
X608417Y-124338D01*
X607455Y-124736D01*
X606630Y-125370D01*
X605996Y-126196D01*
X605598Y-127157D01*
X605462Y-128189D01*
X605598Y-129221D01*
X605996Y-130182D01*
X606630Y-131008D01*
X607455Y-131642D01*
X608417Y-132040D01*
X609449Y-132176D01*
X610481Y-132040D01*
X611442Y-131642D01*
X612268Y-131008D01*
X612901Y-130182D01*
X613300Y-129221D01*
X613436Y-128189D01*
X613300Y-127157D01*
X612901Y-126196D01*
X612268Y-125370D01*
X611442Y-124736D01*
X610481Y-124338D01*
X609449Y-124202D01*
D02*
G37*
G36*
X150233Y-125527D02*
X149530Y-125667D01*
X148935Y-126065D01*
X148537Y-126660D01*
X148398Y-127362D01*
X148537Y-128065D01*
X148935Y-128660D01*
X149097Y-128768D01*
X149329Y-129214D01*
X149207Y-129397D01*
X148931Y-129809D01*
X148791Y-130512D01*
X148931Y-131214D01*
X149329Y-131809D01*
X149924Y-132207D01*
X150627Y-132347D01*
X151329Y-132207D01*
X151924Y-131809D01*
X152322Y-131214D01*
X152462Y-130512D01*
X152322Y-129809D01*
X151924Y-129214D01*
X151763Y-129106D01*
X151531Y-128660D01*
X151653Y-128477D01*
X151928Y-128065D01*
X152068Y-127362D01*
X151928Y-126660D01*
X151531Y-126065D01*
X150935Y-125667D01*
X150233Y-125527D01*
D02*
G37*
G36*
X255906Y-129661D02*
X255203Y-129800D01*
X254608Y-130198D01*
X254210Y-130794D01*
X254070Y-131496D01*
X254210Y-132198D01*
X254608Y-132794D01*
X255203Y-133192D01*
X255906Y-133331D01*
X256608Y-133192D01*
X257203Y-132794D01*
X257601Y-132198D01*
X257741Y-131496D01*
X257601Y-130794D01*
X257203Y-130198D01*
X256608Y-129800D01*
X255906Y-129661D01*
D02*
G37*
G36*
X422835Y-129956D02*
X422132Y-130096D01*
X421537Y-130494D01*
X421139Y-131089D01*
X420999Y-131791D01*
X421139Y-132494D01*
X421537Y-133089D01*
X422132Y-133487D01*
X422835Y-133627D01*
X423537Y-133487D01*
X424132Y-133089D01*
X424530Y-132494D01*
X424670Y-131791D01*
X424530Y-131089D01*
X424132Y-130494D01*
X423537Y-130096D01*
X422835Y-129956D01*
D02*
G37*
G36*
X594488Y-130842D02*
X593786Y-130982D01*
X593190Y-131379D01*
X592793Y-131975D01*
X592653Y-132677D01*
X592793Y-133379D01*
X593190Y-133975D01*
X593786Y-134373D01*
X594488Y-134512D01*
X595190Y-134373D01*
X595786Y-133975D01*
X596184Y-133379D01*
X596323Y-132677D01*
X596184Y-131975D01*
X595786Y-131379D01*
X595190Y-130982D01*
X594488Y-130842D01*
D02*
G37*
G36*
X186847Y-133401D02*
X186145Y-133541D01*
X185549Y-133939D01*
X185151Y-134534D01*
X185012Y-135236D01*
X185151Y-135939D01*
X185549Y-136534D01*
X186145Y-136932D01*
X186847Y-137072D01*
X187549Y-136932D01*
X188145Y-136534D01*
X188542Y-135939D01*
X188682Y-135236D01*
X188542Y-134534D01*
X188145Y-133939D01*
X187549Y-133541D01*
X186847Y-133401D01*
D02*
G37*
G36*
X91044Y-136101D02*
X90342Y-136240D01*
X89747Y-136638D01*
X89349Y-137233D01*
X89299Y-137483D01*
X88789D01*
X88740Y-137233D01*
X88342Y-136638D01*
X87747Y-136240D01*
X87044Y-136101D01*
X86342Y-136240D01*
X85747Y-136638D01*
X85349Y-137233D01*
X85299Y-137483D01*
X84789D01*
X84740Y-137233D01*
X84342Y-136638D01*
X83747Y-136240D01*
X83044Y-136101D01*
X82342Y-136240D01*
X81747Y-136638D01*
X81349Y-137233D01*
X81299Y-137483D01*
X80789D01*
X80740Y-137233D01*
X80342Y-136638D01*
X79747Y-136240D01*
X79044Y-136101D01*
X78342Y-136240D01*
X77747Y-136638D01*
X77349Y-137233D01*
X77209Y-137936D01*
X77349Y-138638D01*
X77747Y-139234D01*
X78342Y-139631D01*
X79044Y-139771D01*
X79244Y-139731D01*
X79349Y-140259D01*
X79747Y-140855D01*
X80342Y-141253D01*
X81044Y-141392D01*
X81747Y-141253D01*
X82342Y-140855D01*
X82740Y-140259D01*
X82845Y-139731D01*
X83044Y-139771D01*
X83747Y-139631D01*
X84342Y-139234D01*
X84740Y-138638D01*
X84789Y-138389D01*
X85299D01*
X85349Y-138638D01*
X85747Y-139234D01*
X86342Y-139631D01*
X87044Y-139771D01*
X87244Y-139731D01*
X87349Y-140259D01*
X87747Y-140855D01*
X88342Y-141253D01*
X89044Y-141392D01*
X89747Y-141253D01*
X90342Y-140855D01*
X90740Y-140259D01*
X90845Y-139731D01*
X91044Y-139771D01*
X91747Y-139631D01*
X92342Y-139234D01*
X92740Y-138638D01*
X92880Y-137936D01*
X92740Y-137233D01*
X92342Y-136638D01*
X91747Y-136240D01*
X91044Y-136101D01*
D02*
G37*
G36*
X172674Y-136551D02*
X171971Y-136690D01*
X171376Y-137088D01*
X170978Y-137683D01*
X170868Y-138236D01*
X170311Y-138125D01*
X169609Y-138265D01*
X169014Y-138663D01*
X168616Y-139258D01*
X168476Y-139961D01*
X168616Y-140663D01*
X169014Y-141258D01*
X169609Y-141656D01*
X170311Y-141796D01*
X171014Y-141656D01*
X171609Y-141258D01*
X172007Y-140663D01*
X172117Y-140110D01*
X172674Y-140221D01*
X173376Y-140081D01*
X173971Y-139683D01*
X174369Y-139088D01*
X174509Y-138386D01*
X174369Y-137683D01*
X173971Y-137088D01*
X173376Y-136690D01*
X172674Y-136551D01*
D02*
G37*
G36*
X126307Y-134389D02*
X125605Y-134528D01*
X125010Y-134926D01*
X124612Y-135522D01*
X124472Y-136224D01*
X124612Y-136926D01*
X125010Y-137522D01*
X125605Y-137919D01*
X126307Y-138059D01*
X127010Y-137919D01*
X127534Y-137569D01*
X127766Y-137915D01*
X128361Y-138313D01*
X129063Y-138453D01*
X129766Y-138313D01*
X130361Y-137915D01*
X130759Y-137320D01*
X130836Y-136933D01*
X131346D01*
X131403Y-137222D01*
X131801Y-137817D01*
X132396Y-138215D01*
X133099Y-138355D01*
X133801Y-138215D01*
X134397Y-137817D01*
X134794Y-137222D01*
X134934Y-136519D01*
X134794Y-135817D01*
X134397Y-135222D01*
X133801Y-134824D01*
X133099Y-134684D01*
X132396Y-134824D01*
X131801Y-135222D01*
X131403Y-135817D01*
X131326Y-136204D01*
X130816D01*
X130759Y-135915D01*
X130361Y-135320D01*
X129766Y-134922D01*
X129063Y-134782D01*
X128361Y-134922D01*
X127837Y-135273D01*
X127605Y-134926D01*
X127010Y-134528D01*
X126307Y-134389D01*
D02*
G37*
G36*
X178185Y-131826D02*
X177483Y-131966D01*
X176888Y-132364D01*
X176490Y-132959D01*
X176350Y-133661D01*
X176490Y-134364D01*
X176866Y-134926D01*
X176928Y-135073D01*
Y-135399D01*
X176866Y-135546D01*
X176490Y-136109D01*
X176350Y-136811D01*
X176490Y-137513D01*
X176888Y-138109D01*
X177483Y-138507D01*
X178185Y-138646D01*
X178888Y-138507D01*
X179483Y-138109D01*
X179881Y-137513D01*
X180021Y-136811D01*
X179881Y-136109D01*
X179505Y-135546D01*
X179443Y-135399D01*
Y-135073D01*
X179505Y-134926D01*
X179881Y-134364D01*
X180021Y-133661D01*
X179881Y-132959D01*
X179483Y-132364D01*
X178888Y-131966D01*
X178185Y-131826D01*
D02*
G37*
G36*
X255906Y-135173D02*
X255203Y-135312D01*
X254608Y-135710D01*
X254210Y-136306D01*
X254070Y-137008D01*
X254210Y-137710D01*
X254608Y-138306D01*
X255203Y-138703D01*
X255906Y-138843D01*
X256608Y-138703D01*
X257203Y-138306D01*
X257601Y-137710D01*
X257741Y-137008D01*
X257601Y-136306D01*
X257203Y-135710D01*
X256608Y-135312D01*
X255906Y-135173D01*
D02*
G37*
G36*
X44001Y-135911D02*
X43298Y-136051D01*
X42703Y-136449D01*
X42305Y-137044D01*
X42165Y-137747D01*
X42305Y-138449D01*
X42703Y-139044D01*
X43298Y-139442D01*
X44001Y-139582D01*
X44703Y-139442D01*
X45298Y-139044D01*
X45696Y-138449D01*
X45836Y-137747D01*
X45696Y-137044D01*
X45298Y-136449D01*
X44703Y-136051D01*
X44001Y-135911D01*
D02*
G37*
G36*
X298031Y-131426D02*
X296974Y-131565D01*
X295988Y-131973D01*
X295142Y-132623D01*
X294493Y-133469D01*
X294085Y-134454D01*
X293945Y-135512D01*
X294085Y-136569D01*
X294493Y-137555D01*
X295142Y-138401D01*
X295988Y-139050D01*
X296974Y-139459D01*
X298031Y-139598D01*
X299089Y-139459D01*
X300075Y-139050D01*
X300921Y-138401D01*
X301570Y-137555D01*
X301978Y-136569D01*
X302118Y-135512D01*
X301978Y-134454D01*
X301570Y-133469D01*
X300921Y-132623D01*
X300075Y-131973D01*
X299089Y-131565D01*
X298031Y-131426D01*
D02*
G37*
G36*
X285827Y-135960D02*
X285124Y-136100D01*
X284529Y-136498D01*
X284131Y-137093D01*
X283992Y-137795D01*
X284131Y-138498D01*
X284529Y-139093D01*
X285124Y-139491D01*
X285827Y-139630D01*
X286529Y-139491D01*
X287124Y-139093D01*
X287522Y-138498D01*
X287662Y-137795D01*
X287522Y-137093D01*
X287124Y-136498D01*
X286529Y-136100D01*
X285827Y-135960D01*
D02*
G37*
G36*
X280709D02*
X280006Y-136100D01*
X279411Y-136498D01*
X279013Y-137093D01*
X278873Y-137795D01*
X279013Y-138498D01*
X279411Y-139093D01*
X280006Y-139491D01*
X280709Y-139630D01*
X281411Y-139491D01*
X282006Y-139093D01*
X282404Y-138498D01*
X282544Y-137795D01*
X282404Y-137093D01*
X282006Y-136498D01*
X281411Y-136100D01*
X280709Y-135960D01*
D02*
G37*
G36*
X223209Y-135980D02*
X222506Y-136119D01*
X221911Y-136517D01*
X221513Y-137113D01*
X221373Y-137815D01*
X221513Y-138517D01*
X221911Y-139113D01*
X222506Y-139511D01*
X223209Y-139650D01*
X223911Y-139511D01*
X224506Y-139113D01*
X224904Y-138517D01*
X225044Y-137815D01*
X224904Y-137113D01*
X224506Y-136517D01*
X223911Y-136119D01*
X223209Y-135980D01*
D02*
G37*
G36*
X321260Y-131484D02*
X320177Y-131626D01*
X319167Y-132045D01*
X318300Y-132710D01*
X317635Y-133577D01*
X317217Y-134586D01*
X317074Y-135669D01*
X317217Y-136752D01*
X317635Y-137762D01*
X318300Y-138629D01*
X319167Y-139294D01*
X320177Y-139712D01*
X321260Y-139855D01*
X322343Y-139712D01*
X323353Y-139294D01*
X324219Y-138629D01*
X324885Y-137762D01*
X325303Y-136752D01*
X325445Y-135669D01*
X325303Y-134586D01*
X324885Y-133577D01*
X324219Y-132710D01*
X323353Y-132045D01*
X322343Y-131626D01*
X321260Y-131484D01*
D02*
G37*
G36*
X68889Y-135618D02*
X68187Y-135758D01*
X67591Y-136156D01*
X67194Y-136751D01*
X67054Y-137453D01*
X67194Y-138156D01*
X67591Y-138751D01*
X68187Y-139149D01*
X68889Y-139289D01*
X69591Y-139149D01*
X69695Y-139080D01*
X69904Y-139393D01*
X70499Y-139790D01*
X71202Y-139930D01*
X71904Y-139790D01*
X72500Y-139393D01*
X72897Y-138797D01*
X73037Y-138095D01*
X72897Y-137393D01*
X72500Y-136797D01*
X71904Y-136399D01*
X71202Y-136260D01*
X70499Y-136399D01*
X70396Y-136469D01*
X70187Y-136156D01*
X69591Y-135758D01*
X68889Y-135618D01*
D02*
G37*
G36*
X204193Y-136422D02*
X203491Y-136562D01*
X202895Y-136959D01*
X202497Y-137555D01*
X202358Y-138257D01*
X202497Y-138959D01*
X202895Y-139555D01*
X203491Y-139953D01*
X204193Y-140092D01*
X204895Y-139953D01*
X205491Y-139555D01*
X205889Y-138959D01*
X206028Y-138257D01*
X205889Y-137555D01*
X205491Y-136959D01*
X204895Y-136562D01*
X204193Y-136422D01*
D02*
G37*
G36*
X199193Y-136844D02*
X198491Y-136984D01*
X197895Y-137382D01*
X197497Y-137977D01*
X197358Y-138680D01*
X197497Y-139382D01*
X197895Y-139977D01*
X198491Y-140375D01*
X199193Y-140515D01*
X199895Y-140375D01*
X200491Y-139977D01*
X200888Y-139382D01*
X201028Y-138680D01*
X200888Y-137977D01*
X200491Y-137382D01*
X199895Y-136984D01*
X199193Y-136844D01*
D02*
G37*
G36*
X228209Y-136885D02*
X227506Y-137025D01*
X226911Y-137423D01*
X226513Y-138018D01*
X226373Y-138721D01*
X226513Y-139423D01*
X226911Y-140018D01*
X227506Y-140416D01*
X228209Y-140556D01*
X228911Y-140416D01*
X229506Y-140018D01*
X229904Y-139423D01*
X230044Y-138721D01*
X229904Y-138018D01*
X229506Y-137423D01*
X228911Y-137025D01*
X228209Y-136885D01*
D02*
G37*
G36*
X233209Y-137397D02*
X232506Y-137537D01*
X231911Y-137935D01*
X231513Y-138530D01*
X231373Y-139232D01*
X231513Y-139935D01*
X231911Y-140530D01*
X232506Y-140928D01*
X233209Y-141068D01*
X233911Y-140928D01*
X234506Y-140530D01*
X234904Y-139935D01*
X235044Y-139232D01*
X234904Y-138530D01*
X234506Y-137935D01*
X233911Y-137537D01*
X233209Y-137397D01*
D02*
G37*
G36*
X162241Y-138169D02*
X161538Y-138309D01*
X160943Y-138706D01*
X160545Y-139302D01*
X160405Y-140004D01*
X160545Y-140706D01*
X160943Y-141302D01*
X161538Y-141700D01*
X162241Y-141839D01*
X162943Y-141700D01*
X163538Y-141302D01*
X163936Y-140706D01*
X164076Y-140004D01*
X163936Y-139302D01*
X163538Y-138706D01*
X162943Y-138309D01*
X162241Y-138169D01*
D02*
G37*
G36*
X150394Y-138322D02*
X149691Y-138462D01*
X149096Y-138860D01*
X148698Y-139455D01*
X148558Y-140157D01*
X148698Y-140860D01*
X149096Y-141455D01*
X149691Y-141853D01*
X150394Y-141993D01*
X151096Y-141853D01*
X151691Y-141455D01*
X152089Y-140860D01*
X152229Y-140157D01*
X152089Y-139455D01*
X151691Y-138860D01*
X151096Y-138462D01*
X150394Y-138322D01*
D02*
G37*
G36*
X276083Y-139306D02*
X275380Y-139446D01*
X274785Y-139844D01*
X274387Y-140439D01*
X274247Y-141142D01*
X274387Y-141844D01*
X274785Y-142439D01*
X275380Y-142837D01*
X276083Y-142977D01*
X276785Y-142837D01*
X277380Y-142439D01*
X277778Y-141844D01*
X277918Y-141142D01*
X277778Y-140439D01*
X277380Y-139844D01*
X276785Y-139446D01*
X276083Y-139306D01*
D02*
G37*
G36*
X255906Y-140291D02*
X255203Y-140430D01*
X254608Y-140828D01*
X254210Y-141424D01*
X254070Y-142126D01*
X254210Y-142828D01*
X254608Y-143424D01*
X255203Y-143822D01*
X255906Y-143961D01*
X256608Y-143822D01*
X257203Y-143424D01*
X257601Y-142828D01*
X257741Y-142126D01*
X257601Y-141424D01*
X257203Y-140828D01*
X256608Y-140430D01*
X255906Y-140291D01*
D02*
G37*
G36*
X284252Y-142259D02*
X283550Y-142399D01*
X282954Y-142797D01*
X282556Y-143392D01*
X282417Y-144095D01*
X282556Y-144797D01*
X282954Y-145392D01*
X283550Y-145790D01*
X284252Y-145930D01*
X284954Y-145790D01*
X285550Y-145392D01*
X285947Y-144797D01*
X286087Y-144095D01*
X285947Y-143392D01*
X285550Y-142797D01*
X284954Y-142399D01*
X284252Y-142259D01*
D02*
G37*
G36*
X591339Y-142653D02*
X590636Y-142793D01*
X590041Y-143191D01*
X589643Y-143786D01*
X589503Y-144488D01*
X589643Y-145191D01*
X590041Y-145786D01*
X590636Y-146184D01*
X591339Y-146324D01*
X592041Y-146184D01*
X592636Y-145786D01*
X593034Y-145191D01*
X593174Y-144488D01*
X593034Y-143786D01*
X592636Y-143191D01*
X592041Y-142793D01*
X591339Y-142653D01*
D02*
G37*
G36*
X496063Y-143440D02*
X495361Y-143580D01*
X494765Y-143978D01*
X494367Y-144573D01*
X494228Y-145276D01*
X494367Y-145978D01*
X494765Y-146573D01*
X495361Y-146971D01*
X496063Y-147111D01*
X496765Y-146971D01*
X497361Y-146573D01*
X497759Y-145978D01*
X497898Y-145276D01*
X497759Y-144573D01*
X497361Y-143978D01*
X496765Y-143580D01*
X496063Y-143440D01*
D02*
G37*
G36*
X500394Y-143834D02*
X499691Y-143974D01*
X499096Y-144372D01*
X498698Y-144967D01*
X498558Y-145669D01*
X498698Y-146372D01*
X499096Y-146967D01*
X499691Y-147365D01*
X500394Y-147504D01*
X501096Y-147365D01*
X501691Y-146967D01*
X502089Y-146372D01*
X502229Y-145669D01*
X502089Y-144967D01*
X501691Y-144372D01*
X501096Y-143974D01*
X500394Y-143834D01*
D02*
G37*
G36*
X491732Y-143440D02*
X491030Y-143580D01*
X490435Y-143978D01*
X490037Y-144573D01*
X489897Y-145276D01*
X490037Y-145978D01*
X490435Y-146573D01*
X491030Y-146971D01*
X491121Y-146989D01*
Y-147499D01*
X491030Y-147517D01*
X490435Y-147915D01*
X490037Y-148510D01*
X489897Y-149213D01*
X490037Y-149915D01*
X490435Y-150510D01*
X491030Y-150908D01*
X491732Y-151048D01*
X492435Y-150908D01*
X493030Y-150510D01*
X493428Y-149915D01*
X493568Y-149213D01*
X493428Y-148510D01*
X493030Y-147915D01*
X492435Y-147517D01*
X492344Y-147499D01*
Y-146989D01*
X492435Y-146971D01*
X493030Y-146573D01*
X493428Y-145978D01*
X493568Y-145276D01*
X493428Y-144573D01*
X493030Y-143978D01*
X492435Y-143580D01*
X491732Y-143440D01*
D02*
G37*
G36*
X619449Y-144202D02*
X618417Y-144338D01*
X617455Y-144736D01*
X616630Y-145370D01*
X615996Y-146196D01*
X615598Y-147157D01*
X615462Y-148189D01*
X615598Y-149221D01*
X615996Y-150182D01*
X616630Y-151008D01*
X617455Y-151642D01*
X618417Y-152040D01*
X619449Y-152176D01*
X620481Y-152040D01*
X621442Y-151642D01*
X622268Y-151008D01*
X622901Y-150182D01*
X623300Y-149221D01*
X623436Y-148189D01*
X623300Y-147157D01*
X622901Y-146196D01*
X622268Y-145370D01*
X621442Y-144736D01*
X620481Y-144338D01*
X619449Y-144202D01*
D02*
G37*
G36*
X609449D02*
X608417Y-144338D01*
X607455Y-144736D01*
X606630Y-145370D01*
X605996Y-146196D01*
X605598Y-147157D01*
X605462Y-148189D01*
X605598Y-149221D01*
X605996Y-150182D01*
X606630Y-151008D01*
X607455Y-151642D01*
X608417Y-152040D01*
X609449Y-152176D01*
X610481Y-152040D01*
X611442Y-151642D01*
X612268Y-151008D01*
X612901Y-150182D01*
X613300Y-149221D01*
X613436Y-148189D01*
X613300Y-147157D01*
X612901Y-146196D01*
X612268Y-145370D01*
X611442Y-144736D01*
X610481Y-144338D01*
X609449Y-144202D01*
D02*
G37*
G36*
X255512Y-145015D02*
X254809Y-145155D01*
X254214Y-145553D01*
X253816Y-146148D01*
X253677Y-146850D01*
X253816Y-147553D01*
X254214Y-148148D01*
X254809Y-148546D01*
X255512Y-148686D01*
X256060Y-148577D01*
X256255Y-149048D01*
X256183Y-149096D01*
X255785Y-149691D01*
X255645Y-150394D01*
X255785Y-151096D01*
X256183Y-151691D01*
X256778Y-152089D01*
X257480Y-152229D01*
X258183Y-152089D01*
X258778Y-151691D01*
X259176Y-151096D01*
X259316Y-150394D01*
X259176Y-149691D01*
X258778Y-149096D01*
X258183Y-148698D01*
X257480Y-148558D01*
X256932Y-148668D01*
X256737Y-148196D01*
X256809Y-148148D01*
X257207Y-147553D01*
X257347Y-146850D01*
X257207Y-146148D01*
X256809Y-145553D01*
X256214Y-145155D01*
X255512Y-145015D01*
D02*
G37*
G36*
X282058Y-149381D02*
X281356Y-149521D01*
X280761Y-149919D01*
X280363Y-150514D01*
X280223Y-151217D01*
X280363Y-151919D01*
X280761Y-152515D01*
X281356Y-152912D01*
X282058Y-153052D01*
X282761Y-152912D01*
X283356Y-152515D01*
X283754Y-151919D01*
X283893Y-151217D01*
X283754Y-150514D01*
X283356Y-149919D01*
X282761Y-149521D01*
X282058Y-149381D01*
D02*
G37*
G36*
X276083Y-150724D02*
X275380Y-150864D01*
X274785Y-151261D01*
X274387Y-151857D01*
X274247Y-152559D01*
X274387Y-153261D01*
X274785Y-153857D01*
X275380Y-154255D01*
X276083Y-154394D01*
X276785Y-154255D01*
X277380Y-153857D01*
X277778Y-153261D01*
X277918Y-152559D01*
X277778Y-151857D01*
X277380Y-151261D01*
X276785Y-150864D01*
X276083Y-150724D01*
D02*
G37*
G36*
X285384Y-152657D02*
X284682Y-152797D01*
X284086Y-153194D01*
X283689Y-153790D01*
X283584Y-154317D01*
X283479Y-154394D01*
X283131Y-154525D01*
X283070Y-154530D01*
X282592Y-154210D01*
X281890Y-154070D01*
X281187Y-154210D01*
X280592Y-154608D01*
X280194Y-155203D01*
X280054Y-155905D01*
X280194Y-156608D01*
X280592Y-157203D01*
X281187Y-157601D01*
X281890Y-157741D01*
X282592Y-157601D01*
X283188Y-157203D01*
X283585Y-156608D01*
X283690Y-156081D01*
X283795Y-156004D01*
X284143Y-155873D01*
X284204Y-155868D01*
X284682Y-156188D01*
X285384Y-156327D01*
X286087Y-156188D01*
X286682Y-155790D01*
X287080Y-155194D01*
X287220Y-154492D01*
X287080Y-153790D01*
X286682Y-153194D01*
X286087Y-152797D01*
X285384Y-152657D01*
D02*
G37*
G36*
X366043Y-152102D02*
X365341Y-152241D01*
X364746Y-152639D01*
X364348Y-153235D01*
X364208Y-153937D01*
X364348Y-154639D01*
X364746Y-155235D01*
X365341Y-155633D01*
X366043Y-155772D01*
X366746Y-155633D01*
X367341Y-155235D01*
X367739Y-154639D01*
X367879Y-153937D01*
X367739Y-153235D01*
X367341Y-152639D01*
X366746Y-152241D01*
X366043Y-152102D01*
D02*
G37*
G36*
X302083Y-151461D02*
X293980D01*
Y-159563D01*
X302083D01*
Y-151461D01*
D02*
G37*
G36*
X363386Y-158795D02*
X362684Y-158934D01*
X362088Y-159332D01*
X361783Y-159788D01*
X361331Y-159850D01*
X361205Y-159823D01*
X361140Y-159726D01*
X360545Y-159328D01*
X359842Y-159188D01*
X359140Y-159328D01*
X358545Y-159726D01*
X358147Y-160321D01*
X358007Y-161024D01*
X358147Y-161726D01*
X358545Y-162321D01*
X359140Y-162719D01*
X359842Y-162859D01*
X360545Y-162719D01*
X361140Y-162321D01*
X361445Y-161865D01*
X361897Y-161804D01*
X362023Y-161831D01*
X362088Y-161928D01*
X362684Y-162326D01*
X363386Y-162465D01*
X364088Y-162326D01*
X364684Y-161928D01*
X365081Y-161332D01*
X365221Y-160630D01*
X365081Y-159928D01*
X364684Y-159332D01*
X364088Y-158934D01*
X363386Y-158795D01*
D02*
G37*
G36*
X586614Y-156826D02*
X585912Y-156966D01*
X585316Y-157364D01*
X584919Y-157959D01*
X584779Y-158661D01*
X584919Y-159364D01*
X585316Y-159959D01*
X585912Y-160357D01*
X586614Y-160497D01*
X587317Y-160357D01*
X587912Y-159959D01*
X588310Y-159364D01*
X588449Y-158661D01*
X588310Y-157959D01*
X587912Y-157364D01*
X587317Y-156966D01*
X586614Y-156826D01*
D02*
G37*
G36*
X325409Y-151520D02*
X317110D01*
Y-159575D01*
X316531Y-159962D01*
X316133Y-160557D01*
X316075Y-160849D01*
X315652Y-160887D01*
X315560Y-160874D01*
X315176Y-160299D01*
X314581Y-159901D01*
X313878Y-159761D01*
X313176Y-159901D01*
X312581Y-160299D01*
X312183Y-160894D01*
X312043Y-161597D01*
X312183Y-162299D01*
X312581Y-162894D01*
X313176Y-163292D01*
X313878Y-163432D01*
X314581Y-163292D01*
X315176Y-162894D01*
X315574Y-162299D01*
X315632Y-162007D01*
X316054Y-161969D01*
X316146Y-161983D01*
X316531Y-162558D01*
X317126Y-162955D01*
X317828Y-163095D01*
X318531Y-162955D01*
X319126Y-162558D01*
X319524Y-161962D01*
X319664Y-161260D01*
X319524Y-160557D01*
X319364Y-160319D01*
X319632Y-159819D01*
X325409D01*
Y-151520D01*
D02*
G37*
G36*
X-3528Y-152395D02*
X-13402D01*
Y-162269D01*
X-3528D01*
Y-152395D01*
D02*
G37*
G36*
X367717Y-158795D02*
X367014Y-158934D01*
X366419Y-159332D01*
X366021Y-159928D01*
X365881Y-160630D01*
X366021Y-161332D01*
X366419Y-161928D01*
X367014Y-162326D01*
X367717Y-162465D01*
X368419Y-162326D01*
X369014Y-161928D01*
X369412Y-161332D01*
X369552Y-160630D01*
X369412Y-159928D01*
X369014Y-159332D01*
X368419Y-158934D01*
X367717Y-158795D01*
D02*
G37*
G36*
X378346Y-159976D02*
X377644Y-160116D01*
X377049Y-160513D01*
X376651Y-161109D01*
X376511Y-161811D01*
X376651Y-162513D01*
X377049Y-163109D01*
X377644Y-163507D01*
X378346Y-163646D01*
X379049Y-163507D01*
X379644Y-163109D01*
X380042Y-162513D01*
X380182Y-161811D01*
X380042Y-161109D01*
X379644Y-160513D01*
X379049Y-160116D01*
X378346Y-159976D01*
D02*
G37*
G36*
X383083Y-160004D02*
X382380Y-160143D01*
X381785Y-160541D01*
X381387Y-161137D01*
X381247Y-161839D01*
X381387Y-162541D01*
X381785Y-163137D01*
X382380Y-163535D01*
X383083Y-163674D01*
X383785Y-163535D01*
X384380Y-163137D01*
X384778Y-162541D01*
X384918Y-161839D01*
X384778Y-161137D01*
X384380Y-160541D01*
X383785Y-160143D01*
X383083Y-160004D01*
D02*
G37*
G36*
X388189Y-160370D02*
X387487Y-160509D01*
X386891Y-160907D01*
X386493Y-161502D01*
X386354Y-162205D01*
X386493Y-162907D01*
X386891Y-163502D01*
X387487Y-163900D01*
X388189Y-164040D01*
X388891Y-163900D01*
X389487Y-163502D01*
X389884Y-162907D01*
X390024Y-162205D01*
X389884Y-161502D01*
X389487Y-160907D01*
X388891Y-160509D01*
X388189Y-160370D01*
D02*
G37*
G36*
X373228Y-160763D02*
X372526Y-160903D01*
X371931Y-161301D01*
X371533Y-161896D01*
X371393Y-162598D01*
X371533Y-163301D01*
X371931Y-163896D01*
X372526Y-164294D01*
X373228Y-164434D01*
X373931Y-164294D01*
X374526Y-163896D01*
X374924Y-163301D01*
X375064Y-162598D01*
X374924Y-161896D01*
X374526Y-161301D01*
X373931Y-160903D01*
X373228Y-160763D01*
D02*
G37*
G36*
X582165Y-162062D02*
X581463Y-162202D01*
X580868Y-162600D01*
X580470Y-163195D01*
X580330Y-163898D01*
X580470Y-164600D01*
X580868Y-165195D01*
X581463Y-165593D01*
X582165Y-165733D01*
X582868Y-165593D01*
X583463Y-165195D01*
X583861Y-164600D01*
X584001Y-163898D01*
X583861Y-163195D01*
X583463Y-162600D01*
X582868Y-162202D01*
X582165Y-162062D01*
D02*
G37*
G36*
X78268Y-152746D02*
X76895Y-152881D01*
X75576Y-153281D01*
X74360Y-153931D01*
X73294Y-154806D01*
X72419Y-155872D01*
X71769Y-157088D01*
X71369Y-158407D01*
X71234Y-159780D01*
X71369Y-161152D01*
X71769Y-162471D01*
X72419Y-163687D01*
X73294Y-164753D01*
X74360Y-165628D01*
X75576Y-166278D01*
X76895Y-166678D01*
X78268Y-166813D01*
X79640Y-166678D01*
X80959Y-166278D01*
X82175Y-165628D01*
X83241Y-164753D01*
X84116Y-163687D01*
X84766Y-162471D01*
X85166Y-161152D01*
X85302Y-159780D01*
X85166Y-158407D01*
X84766Y-157088D01*
X84116Y-155872D01*
X83241Y-154806D01*
X82175Y-153931D01*
X80959Y-153281D01*
X79640Y-152881D01*
X78268Y-152746D01*
D02*
G37*
G36*
X348031Y-163913D02*
X347329Y-164052D01*
X346734Y-164450D01*
X346336Y-165046D01*
X346196Y-165748D01*
X346336Y-166450D01*
X346734Y-167046D01*
X347329Y-167444D01*
X348031Y-167583D01*
X348734Y-167444D01*
X349329Y-167046D01*
X349727Y-166450D01*
X349867Y-165748D01*
X349727Y-165046D01*
X349329Y-164450D01*
X348734Y-164052D01*
X348031Y-163913D01*
D02*
G37*
G36*
X310236D02*
X309534Y-164052D01*
X308939Y-164450D01*
X308541Y-165046D01*
X308401Y-165748D01*
X308541Y-166450D01*
X308939Y-167046D01*
X309534Y-167444D01*
X310236Y-167583D01*
X310939Y-167444D01*
X311534Y-167046D01*
X311932Y-166450D01*
X312071Y-165748D01*
X311932Y-165046D01*
X311534Y-164450D01*
X310939Y-164052D01*
X310236Y-163913D01*
D02*
G37*
G36*
X422835Y-164449D02*
X422132Y-164589D01*
X421537Y-164987D01*
X421139Y-165582D01*
X420999Y-166284D01*
X421139Y-166987D01*
X421537Y-167582D01*
X422132Y-167980D01*
X422835Y-168120D01*
X423537Y-167980D01*
X424132Y-167582D01*
X424530Y-166987D01*
X424670Y-166284D01*
X424530Y-165582D01*
X424132Y-164987D01*
X423537Y-164589D01*
X422835Y-164449D01*
D02*
G37*
G36*
X321260Y-164306D02*
X320557Y-164446D01*
X319962Y-164844D01*
X319564Y-165439D01*
X319425Y-166142D01*
X319564Y-166844D01*
X319962Y-167439D01*
X320557Y-167837D01*
X321260Y-167977D01*
X321962Y-167837D01*
X322214Y-167669D01*
X322324Y-167833D01*
X322920Y-168231D01*
X323622Y-168371D01*
X324324Y-168231D01*
X324920Y-167833D01*
X325318Y-167238D01*
X325457Y-166535D01*
X325318Y-165833D01*
X324920Y-165238D01*
X324324Y-164840D01*
X323622Y-164700D01*
X322920Y-164840D01*
X322667Y-165008D01*
X322558Y-164844D01*
X321962Y-164446D01*
X321260Y-164306D01*
D02*
G37*
G36*
X427843Y-165131D02*
X427141Y-165271D01*
X426545Y-165669D01*
X426148Y-166264D01*
X426008Y-166966D01*
X426148Y-167669D01*
X426545Y-168264D01*
X427141Y-168662D01*
X427843Y-168802D01*
X428545Y-168662D01*
X429141Y-168264D01*
X429539Y-167669D01*
X429678Y-166966D01*
X429539Y-166264D01*
X429141Y-165669D01*
X428545Y-165271D01*
X427843Y-165131D01*
D02*
G37*
G36*
X378594D02*
X377891Y-165271D01*
X377296Y-165669D01*
X376898Y-166264D01*
X376759Y-166966D01*
X376898Y-167669D01*
X377296Y-168264D01*
X377891Y-168662D01*
X378594Y-168802D01*
X379296Y-168662D01*
X379891Y-168264D01*
X380289Y-167669D01*
X380429Y-166966D01*
X380289Y-166264D01*
X379891Y-165669D01*
X379296Y-165271D01*
X378594Y-165131D01*
D02*
G37*
G36*
X342808D02*
X342106Y-165271D01*
X341510Y-165669D01*
X341112Y-166264D01*
X340973Y-166966D01*
X341112Y-167669D01*
X341510Y-168264D01*
X342106Y-168662D01*
X342808Y-168802D01*
X343510Y-168662D01*
X344106Y-168264D01*
X344504Y-167669D01*
X344643Y-166966D01*
X344504Y-166264D01*
X344106Y-165669D01*
X343510Y-165271D01*
X342808Y-165131D01*
D02*
G37*
G36*
X218110Y-157750D02*
X216934Y-157866D01*
X215803Y-158209D01*
X214761Y-158767D01*
X213847Y-159516D01*
X213097Y-160430D01*
X212540Y-161472D01*
X212197Y-162603D01*
X212081Y-163779D01*
X212197Y-164956D01*
X212540Y-166087D01*
X213097Y-167129D01*
X213847Y-168043D01*
X214761Y-168792D01*
X215803Y-169350D01*
X216934Y-169693D01*
X218110Y-169808D01*
X219286Y-169693D01*
X220417Y-169350D01*
X221460Y-168792D01*
X222373Y-168043D01*
X223123Y-167129D01*
X223680Y-166087D01*
X224023Y-164956D01*
X224139Y-163779D01*
X224023Y-162603D01*
X223680Y-161472D01*
X223123Y-160430D01*
X222373Y-159516D01*
X221460Y-158767D01*
X220417Y-158209D01*
X219286Y-157866D01*
X218110Y-157750D01*
D02*
G37*
G36*
X58268D02*
X57091Y-157866D01*
X55961Y-158209D01*
X54918Y-158767D01*
X54005Y-159516D01*
X53255Y-160430D01*
X52698Y-161472D01*
X52355Y-162603D01*
X52239Y-163779D01*
X52355Y-164956D01*
X52698Y-166087D01*
X53255Y-167129D01*
X54005Y-168043D01*
X54918Y-168792D01*
X55961Y-169350D01*
X57091Y-169693D01*
X58268Y-169808D01*
X59444Y-169693D01*
X60575Y-169350D01*
X61617Y-168792D01*
X62531Y-168043D01*
X63281Y-167129D01*
X63838Y-166087D01*
X64181Y-164956D01*
X64297Y-163779D01*
X64181Y-162603D01*
X63838Y-161472D01*
X63281Y-160430D01*
X62531Y-159516D01*
X61617Y-158767D01*
X60575Y-158209D01*
X59444Y-157866D01*
X58268Y-157750D01*
D02*
G37*
G36*
X383071Y-166275D02*
X382369Y-166415D01*
X381773Y-166813D01*
X381375Y-167408D01*
X381236Y-168110D01*
X381375Y-168813D01*
X381773Y-169408D01*
X382369Y-169806D01*
X383071Y-169946D01*
X383773Y-169806D01*
X384369Y-169408D01*
X384766Y-168813D01*
X384906Y-168110D01*
X384766Y-167408D01*
X384369Y-166813D01*
X383773Y-166415D01*
X383071Y-166275D01*
D02*
G37*
G36*
X393701Y-167062D02*
X392999Y-167202D01*
X392403Y-167600D01*
X392005Y-168195D01*
X391865Y-168898D01*
X392005Y-169600D01*
X392403Y-170195D01*
X392999Y-170593D01*
X393701Y-170733D01*
X394403Y-170593D01*
X394999Y-170195D01*
X395396Y-169600D01*
X395536Y-168898D01*
X395396Y-168195D01*
X394999Y-167600D01*
X394403Y-167202D01*
X393701Y-167062D01*
D02*
G37*
G36*
X581890Y-172180D02*
X581187Y-172320D01*
X580592Y-172718D01*
X580194Y-173313D01*
X580055Y-174016D01*
X580194Y-174718D01*
X580592Y-175313D01*
X581187Y-175711D01*
X581890Y-175851D01*
X582592Y-175711D01*
X583187Y-175313D01*
X583585Y-174718D01*
X583725Y-174016D01*
X583585Y-173313D01*
X583187Y-172718D01*
X582592Y-172320D01*
X581890Y-172180D01*
D02*
G37*
G36*
X421313Y-172949D02*
X420611Y-173089D01*
X420015Y-173486D01*
X419617Y-174082D01*
X419478Y-174784D01*
X419514Y-174966D01*
X419096Y-175049D01*
X418500Y-175447D01*
X418102Y-176042D01*
X417963Y-176745D01*
X418102Y-177447D01*
X418500Y-178042D01*
X419096Y-178440D01*
X419798Y-178580D01*
X420500Y-178440D01*
X421096Y-178042D01*
X421493Y-177447D01*
X421633Y-176745D01*
X421597Y-176563D01*
X422015Y-176480D01*
X422611Y-176082D01*
X423009Y-175487D01*
X423148Y-174784D01*
X423009Y-174082D01*
X422611Y-173486D01*
X422015Y-173089D01*
X421313Y-172949D01*
D02*
G37*
G36*
X200610Y-164846D02*
X199238Y-164981D01*
X197918Y-165381D01*
X196703Y-166031D01*
X195637Y-166906D01*
X194762Y-167972D01*
X194112Y-169188D01*
X193712Y-170507D01*
X193576Y-171879D01*
X193712Y-173252D01*
X194112Y-174571D01*
X194762Y-175787D01*
X195637Y-176853D01*
X196703Y-177728D01*
X197918Y-178378D01*
X199238Y-178778D01*
X200610Y-178913D01*
X201982Y-178778D01*
X203302Y-178378D01*
X204518Y-177728D01*
X205584Y-176853D01*
X206459Y-175787D01*
X207109Y-174571D01*
X207509Y-173252D01*
X207644Y-171879D01*
X207509Y-170507D01*
X207109Y-169188D01*
X206459Y-167972D01*
X205584Y-166906D01*
X204518Y-166031D01*
X203302Y-165381D01*
X201982Y-164981D01*
X200610Y-164846D01*
D02*
G37*
G36*
X-10630Y-176511D02*
X-11332Y-176651D01*
X-11928Y-177049D01*
X-12325Y-177644D01*
X-12465Y-178347D01*
X-12325Y-179049D01*
X-11928Y-179644D01*
X-11332Y-180042D01*
X-10630Y-180182D01*
X-9928Y-180042D01*
X-9332Y-179644D01*
X-8934Y-179049D01*
X-8795Y-178347D01*
X-8934Y-177644D01*
X-9332Y-177049D01*
X-9928Y-176651D01*
X-10630Y-176511D01*
D02*
G37*
G36*
X586221Y-176905D02*
X585518Y-177045D01*
X584923Y-177442D01*
X584525Y-178038D01*
X584385Y-178740D01*
X584525Y-179443D01*
X584923Y-180038D01*
X585518Y-180436D01*
X586221Y-180575D01*
X586923Y-180436D01*
X587518Y-180038D01*
X587916Y-179443D01*
X588056Y-178740D01*
X587916Y-178038D01*
X587518Y-177442D01*
X586923Y-177045D01*
X586221Y-176905D01*
D02*
G37*
G36*
X426772Y-177692D02*
X426069Y-177832D01*
X425474Y-178230D01*
X425076Y-178825D01*
X424936Y-179528D01*
X425076Y-180230D01*
X425474Y-180825D01*
X426069Y-181223D01*
X426772Y-181363D01*
X427474Y-181223D01*
X428069Y-180825D01*
X428467Y-180230D01*
X428607Y-179528D01*
X428467Y-178825D01*
X428069Y-178230D01*
X427474Y-177832D01*
X426772Y-177692D01*
D02*
G37*
G36*
X334252Y-178480D02*
X333550Y-178619D01*
X332954Y-179017D01*
X332556Y-179613D01*
X332417Y-180315D01*
X332556Y-181017D01*
X332954Y-181613D01*
X333550Y-182010D01*
X334252Y-182150D01*
X334954Y-182010D01*
X335550Y-181613D01*
X335551Y-181610D01*
X336082Y-181716D01*
X336100Y-181805D01*
X336498Y-182400D01*
X337093Y-182798D01*
X337795Y-182938D01*
X338498Y-182798D01*
X339093Y-182400D01*
X339491Y-181805D01*
X339631Y-181102D01*
X339491Y-180400D01*
X339093Y-179805D01*
X338498Y-179407D01*
X337795Y-179267D01*
X337093Y-179407D01*
X336498Y-179805D01*
X336496Y-179807D01*
X335965Y-179701D01*
X335947Y-179613D01*
X335550Y-179017D01*
X334954Y-178619D01*
X334252Y-178480D01*
D02*
G37*
G36*
X326705Y-177224D02*
X326003Y-177364D01*
X325407Y-177761D01*
X325009Y-178357D01*
X324870Y-179059D01*
X325009Y-179762D01*
X325407Y-180357D01*
X326003Y-180755D01*
X326705Y-180894D01*
X327407Y-180755D01*
X327610Y-180619D01*
X327971Y-180980D01*
X327832Y-181187D01*
X327692Y-181890D01*
X327786Y-182359D01*
X327698Y-182691D01*
X327429Y-182889D01*
X326956Y-182983D01*
X326529Y-183268D01*
X326181Y-183342D01*
X325834Y-183268D01*
X325407Y-182983D01*
X324705Y-182843D01*
X324003Y-182983D01*
X323407Y-183380D01*
X323009Y-183976D01*
X322870Y-184678D01*
X323009Y-185381D01*
X323407Y-185976D01*
X324003Y-186374D01*
X324705Y-186513D01*
X325407Y-186374D01*
X325834Y-186089D01*
X326181Y-186014D01*
X326529Y-186089D01*
X326956Y-186374D01*
X327658Y-186513D01*
X328360Y-186374D01*
X328956Y-185976D01*
X329353Y-185381D01*
X329493Y-184678D01*
X329400Y-184209D01*
X329487Y-183877D01*
X329757Y-183679D01*
X330230Y-183585D01*
X330825Y-183187D01*
X331223Y-182592D01*
X331363Y-181890D01*
X331223Y-181187D01*
X330825Y-180592D01*
X330230Y-180194D01*
X329528Y-180054D01*
X328825Y-180194D01*
X328622Y-180330D01*
X328262Y-179969D01*
X328401Y-179762D01*
X328540Y-179059D01*
X328401Y-178357D01*
X328003Y-177761D01*
X327407Y-177364D01*
X326705Y-177224D01*
D02*
G37*
G36*
X390462Y-179645D02*
X389649Y-179807D01*
X388960Y-180267D01*
X388500Y-180956D01*
X388338Y-181769D01*
X388500Y-182582D01*
X388960Y-183271D01*
X389649Y-183731D01*
X390462Y-183893D01*
X391275Y-183731D01*
X391964Y-183271D01*
X392424Y-182582D01*
X392586Y-181769D01*
X392424Y-180956D01*
X391964Y-180267D01*
X391275Y-179807D01*
X390462Y-179645D01*
D02*
G37*
G36*
X311722D02*
X310909Y-179807D01*
X310220Y-180267D01*
X309760Y-180956D01*
X309598Y-181769D01*
X309760Y-182582D01*
X310220Y-183271D01*
X310909Y-183731D01*
X311722Y-183893D01*
X312535Y-183731D01*
X313224Y-183271D01*
X313684Y-182582D01*
X313846Y-181769D01*
X313684Y-180956D01*
X313224Y-180267D01*
X312535Y-179807D01*
X311722Y-179645D01*
D02*
G37*
G36*
X453193Y-170117D02*
X451839Y-170251D01*
X450537Y-170646D01*
X449338Y-171287D01*
X448286Y-172150D01*
X447423Y-173201D01*
X446782Y-174401D01*
X446387Y-175703D01*
X446254Y-177056D01*
X446387Y-178410D01*
X446782Y-179712D01*
X447423Y-180912D01*
X448286Y-181963D01*
X449338Y-182826D01*
X450537Y-183467D01*
X451839Y-183862D01*
X453193Y-183995D01*
X454546Y-183862D01*
X455848Y-183467D01*
X457048Y-182826D01*
X458099Y-181963D01*
X458962Y-180912D01*
X459604Y-179712D01*
X459998Y-178410D01*
X460132Y-177056D01*
X459998Y-175703D01*
X459604Y-174401D01*
X458962Y-173201D01*
X458099Y-172150D01*
X457048Y-171287D01*
X455848Y-170646D01*
X454546Y-170251D01*
X453193Y-170117D01*
D02*
G37*
G36*
X256593D02*
X255239Y-170251D01*
X253937Y-170646D01*
X252738Y-171287D01*
X251686Y-172150D01*
X250823Y-173201D01*
X250182Y-174401D01*
X249787Y-175703D01*
X249654Y-177056D01*
X249787Y-178410D01*
X250182Y-179712D01*
X250823Y-180912D01*
X251686Y-181963D01*
X252738Y-182826D01*
X253937Y-183467D01*
X255239Y-183862D01*
X256593Y-183995D01*
X257946Y-183862D01*
X259248Y-183467D01*
X260448Y-182826D01*
X261499Y-181963D01*
X262362Y-180912D01*
X263003Y-179712D01*
X263398Y-178410D01*
X263532Y-177056D01*
X263398Y-175703D01*
X263003Y-174401D01*
X262362Y-173201D01*
X261499Y-172150D01*
X260448Y-171287D01*
X259248Y-170646D01*
X257946Y-170251D01*
X256593Y-170117D01*
D02*
G37*
G36*
X35827Y-183920D02*
X35124Y-184060D01*
X34834Y-184254D01*
X34449Y-184422D01*
X34064Y-184254D01*
X33773Y-184060D01*
X33071Y-183920D01*
X32368Y-184060D01*
X31773Y-184457D01*
X31375Y-185053D01*
X31236Y-185755D01*
X31375Y-186457D01*
X31773Y-187053D01*
X32368Y-187451D01*
X33071Y-187590D01*
X33773Y-187451D01*
X34064Y-187257D01*
X34449Y-187088D01*
X34834Y-187257D01*
X35124Y-187451D01*
X35827Y-187590D01*
X36529Y-187451D01*
X37124Y-187053D01*
X37522Y-186457D01*
X37662Y-185755D01*
X37522Y-185053D01*
X37124Y-184457D01*
X36529Y-184060D01*
X35827Y-183920D01*
D02*
G37*
G36*
X381890Y-182023D02*
X381187Y-182163D01*
X380592Y-182561D01*
X380194Y-183156D01*
X380054Y-183858D01*
X380194Y-184561D01*
X380592Y-185156D01*
X381187Y-185554D01*
X381890Y-185694D01*
X382592Y-185554D01*
X383117Y-185203D01*
X383348Y-185550D01*
X383943Y-185948D01*
X384646Y-186087D01*
X385348Y-185948D01*
X385943Y-185550D01*
X386341Y-184954D01*
X386481Y-184252D01*
X386341Y-183550D01*
X385943Y-182954D01*
X385348Y-182556D01*
X384646Y-182417D01*
X383943Y-182556D01*
X383419Y-182907D01*
X383188Y-182561D01*
X382592Y-182163D01*
X381890Y-182023D01*
D02*
G37*
G36*
X275590Y-182417D02*
X274888Y-182556D01*
X274293Y-182954D01*
X273895Y-183550D01*
X273755Y-184252D01*
X273895Y-184954D01*
X274293Y-185550D01*
X274888Y-185948D01*
X275590Y-186087D01*
X276293Y-185948D01*
X276888Y-185550D01*
X277286Y-184954D01*
X277426Y-184252D01*
X277286Y-183550D01*
X276888Y-182954D01*
X276293Y-182556D01*
X275590Y-182417D01*
D02*
G37*
G36*
X299606Y-183598D02*
X298904Y-183738D01*
X298309Y-184135D01*
X297911Y-184731D01*
X297771Y-185433D01*
X297911Y-186135D01*
X298309Y-186731D01*
X298904Y-187129D01*
X299606Y-187268D01*
X300309Y-187129D01*
X300904Y-186731D01*
X301302Y-186135D01*
X301442Y-185433D01*
X301302Y-184731D01*
X300904Y-184135D01*
X300309Y-183738D01*
X299606Y-183598D01*
D02*
G37*
G36*
X9843Y-183920D02*
X9140Y-184060D01*
X8545Y-184457D01*
X8147Y-185053D01*
X8007Y-185755D01*
X8147Y-186457D01*
X8545Y-187053D01*
X9140Y-187451D01*
X9843Y-187590D01*
X10545Y-187451D01*
X11140Y-187053D01*
X11538Y-186457D01*
X11678Y-185755D01*
X11538Y-185053D01*
X11140Y-184457D01*
X10545Y-184060D01*
X9843Y-183920D01*
D02*
G37*
G36*
X611614Y-184272D02*
X610912Y-184412D01*
X610316Y-184810D01*
X609919Y-185405D01*
X609779Y-186107D01*
X609919Y-186810D01*
X610316Y-187405D01*
X610912Y-187803D01*
X611614Y-187943D01*
X612317Y-187803D01*
X612912Y-187405D01*
X613310Y-186810D01*
X613449Y-186107D01*
X613310Y-185405D01*
X612912Y-184810D01*
X612317Y-184412D01*
X611614Y-184272D01*
D02*
G37*
G36*
X561024Y-181629D02*
X560321Y-181769D01*
X559726Y-182167D01*
X559328Y-182762D01*
X559188Y-183465D01*
X559328Y-184167D01*
X559704Y-184730D01*
X559766Y-184876D01*
Y-185202D01*
X559704Y-185349D01*
X559328Y-185912D01*
X559188Y-186614D01*
X559328Y-187317D01*
X559726Y-187912D01*
X560321Y-188310D01*
X561024Y-188449D01*
X561726Y-188310D01*
X562321Y-187912D01*
X562719Y-187317D01*
X562859Y-186614D01*
X562719Y-185912D01*
X562343Y-185349D01*
X562281Y-185202D01*
Y-184876D01*
X562343Y-184730D01*
X562719Y-184167D01*
X562859Y-183465D01*
X562719Y-182762D01*
X562321Y-182167D01*
X561726Y-181769D01*
X561024Y-181629D01*
D02*
G37*
G36*
X292815Y-185271D02*
X292113Y-185411D01*
X291517Y-185809D01*
X291119Y-186404D01*
X290980Y-187106D01*
X291119Y-187809D01*
X291517Y-188404D01*
X292113Y-188802D01*
X292815Y-188942D01*
X293517Y-188802D01*
X294113Y-188404D01*
X294511Y-187809D01*
X294650Y-187106D01*
X294511Y-186404D01*
X294113Y-185809D01*
X293517Y-185411D01*
X292815Y-185271D01*
D02*
G37*
G36*
X-23622Y-175330D02*
X-24324Y-175470D01*
X-24920Y-175868D01*
X-25318Y-176463D01*
X-25457Y-177165D01*
X-25318Y-177868D01*
X-24920Y-178463D01*
X-24324Y-178861D01*
X-24234Y-178879D01*
Y-179389D01*
X-24324Y-179407D01*
X-24920Y-179805D01*
X-25318Y-180400D01*
X-25457Y-181102D01*
X-25318Y-181805D01*
X-25032Y-182231D01*
X-24958Y-182579D01*
X-25032Y-182926D01*
X-25318Y-183353D01*
X-25457Y-184055D01*
X-25318Y-184757D01*
X-24920Y-185353D01*
X-24324Y-185751D01*
X-24234Y-185769D01*
Y-186278D01*
X-24324Y-186297D01*
X-24920Y-186694D01*
X-25318Y-187290D01*
X-25457Y-187992D01*
X-25318Y-188695D01*
X-24920Y-189290D01*
X-24324Y-189688D01*
X-23622Y-189827D01*
X-22920Y-189688D01*
X-22324Y-189290D01*
X-21926Y-188695D01*
X-21787Y-187992D01*
X-21926Y-187290D01*
X-22324Y-186694D01*
X-22920Y-186297D01*
X-23010Y-186278D01*
Y-185769D01*
X-22920Y-185751D01*
X-22324Y-185353D01*
X-21926Y-184757D01*
X-21787Y-184055D01*
X-21926Y-183353D01*
X-22212Y-182926D01*
X-22286Y-182579D01*
X-22212Y-182231D01*
X-21926Y-181805D01*
X-21787Y-181102D01*
X-21926Y-180400D01*
X-22324Y-179805D01*
X-22920Y-179407D01*
X-23010Y-179389D01*
Y-178879D01*
X-22920Y-178861D01*
X-22324Y-178463D01*
X-21926Y-177868D01*
X-21787Y-177165D01*
X-21926Y-176463D01*
X-22324Y-175868D01*
X-22920Y-175470D01*
X-23622Y-175330D01*
D02*
G37*
G36*
X281890Y-186747D02*
X281187Y-186887D01*
X280592Y-187285D01*
X280194Y-187880D01*
X280054Y-188583D01*
X280194Y-189285D01*
X280592Y-189880D01*
X281187Y-190278D01*
X281890Y-190418D01*
X282592Y-190278D01*
X283188Y-189880D01*
X283585Y-189285D01*
X283725Y-188583D01*
X283585Y-187880D01*
X283188Y-187285D01*
X282592Y-186887D01*
X281890Y-186747D01*
D02*
G37*
G36*
X274803D02*
X274101Y-186887D01*
X273505Y-187285D01*
X273108Y-187880D01*
X272968Y-188583D01*
X273108Y-189285D01*
X273505Y-189880D01*
X274101Y-190278D01*
X274803Y-190418D01*
X275505Y-190278D01*
X276101Y-189880D01*
X276499Y-189285D01*
X276638Y-188583D01*
X276499Y-187880D01*
X276101Y-187285D01*
X275505Y-186887D01*
X274803Y-186747D01*
D02*
G37*
G36*
X591339Y-187928D02*
X590636Y-188068D01*
X590041Y-188466D01*
X589643Y-189061D01*
X589503Y-189764D01*
X589643Y-190466D01*
X590041Y-191061D01*
X590636Y-191459D01*
X591339Y-191599D01*
X592041Y-191459D01*
X592636Y-191061D01*
X593034Y-190466D01*
X593174Y-189764D01*
X593034Y-189061D01*
X592636Y-188466D01*
X592041Y-188068D01*
X591339Y-187928D01*
D02*
G37*
G36*
X30709Y-188576D02*
X30006Y-188716D01*
X29411Y-189113D01*
X29013Y-189709D01*
X28873Y-190411D01*
X29013Y-191113D01*
X29411Y-191709D01*
X30006Y-192107D01*
X30709Y-192246D01*
X31411Y-192107D01*
X32006Y-191709D01*
X32404Y-191113D01*
X32544Y-190411D01*
X32404Y-189709D01*
X32006Y-189113D01*
X31411Y-188716D01*
X30709Y-188576D01*
D02*
G37*
G36*
X13780Y-188716D02*
X13077Y-188856D01*
X12482Y-189253D01*
X12084Y-189849D01*
X11944Y-190551D01*
X12084Y-191253D01*
X12482Y-191849D01*
X13077Y-192247D01*
X13780Y-192386D01*
X14482Y-192247D01*
X15077Y-191849D01*
X15475Y-191253D01*
X15615Y-190551D01*
X15475Y-189849D01*
X15077Y-189253D01*
X14482Y-188856D01*
X13780Y-188716D01*
D02*
G37*
G36*
X295669Y-189503D02*
X294967Y-189643D01*
X294372Y-190041D01*
X293974Y-190636D01*
X293834Y-191339D01*
X293974Y-192041D01*
X294372Y-192636D01*
X294967Y-193034D01*
X295669Y-193174D01*
X296372Y-193034D01*
X296967Y-192636D01*
X297365Y-192041D01*
X297505Y-191339D01*
X297365Y-190636D01*
X296967Y-190041D01*
X296372Y-189643D01*
X295669Y-189503D01*
D02*
G37*
G36*
X19682Y-190684D02*
X18980Y-190824D01*
X18384Y-191222D01*
X17986Y-191817D01*
X17846Y-192520D01*
X17986Y-193222D01*
X18384Y-193817D01*
X18980Y-194215D01*
X19682Y-194355D01*
X20384Y-194215D01*
X20979Y-193817D01*
X21377Y-193222D01*
X21517Y-192520D01*
X21377Y-191817D01*
X20979Y-191222D01*
X20384Y-190824D01*
X19682Y-190684D01*
D02*
G37*
G36*
X583858Y-191078D02*
X583156Y-191218D01*
X582560Y-191616D01*
X582163Y-192211D01*
X582023Y-192913D01*
X582163Y-193616D01*
X582560Y-194211D01*
X583156Y-194609D01*
X583858Y-194749D01*
X584561Y-194609D01*
X585156Y-194211D01*
X585554Y-193616D01*
X585694Y-192913D01*
X585554Y-192211D01*
X585156Y-191616D01*
X584561Y-191218D01*
X583858Y-191078D01*
D02*
G37*
G36*
X399213Y-191472D02*
X398510Y-191612D01*
X397915Y-192009D01*
X397517Y-192605D01*
X397377Y-193307D01*
X397517Y-194009D01*
X397915Y-194605D01*
X398510Y-195003D01*
X399213Y-195142D01*
X399915Y-195003D01*
X400510Y-194605D01*
X400908Y-194009D01*
X401048Y-193307D01*
X400908Y-192605D01*
X400510Y-192009D01*
X399915Y-191612D01*
X399213Y-191472D01*
D02*
G37*
G36*
X322835Y-194228D02*
X322132Y-194367D01*
X321537Y-194765D01*
X321139Y-195361D01*
X321121Y-195449D01*
X320591Y-195555D01*
X320589Y-195553D01*
X319994Y-195155D01*
X319291Y-195015D01*
X318589Y-195155D01*
X317994Y-195553D01*
X317596Y-196148D01*
X317456Y-196850D01*
X317596Y-197553D01*
X317994Y-198148D01*
X318589Y-198546D01*
X319291Y-198686D01*
X319994Y-198546D01*
X320589Y-198148D01*
X320987Y-197553D01*
X321005Y-197464D01*
X321535Y-197358D01*
X321537Y-197361D01*
X322132Y-197758D01*
X322835Y-197898D01*
X323537Y-197758D01*
X324132Y-197361D01*
X324530Y-196765D01*
X324670Y-196063D01*
X324530Y-195361D01*
X324132Y-194765D01*
X323537Y-194367D01*
X322835Y-194228D01*
D02*
G37*
G36*
X341774Y-194491D02*
X341071Y-194631D01*
X340476Y-195028D01*
X340078Y-195624D01*
X340012Y-195954D01*
X339503D01*
X339469Y-195787D01*
X339071Y-195192D01*
X338476Y-194794D01*
X337774Y-194654D01*
X337071Y-194794D01*
X336476Y-195192D01*
X336078Y-195787D01*
X335938Y-196489D01*
X336078Y-197192D01*
X336476Y-197787D01*
X337071Y-198185D01*
X337774Y-198325D01*
X338476Y-198185D01*
X339071Y-197787D01*
X339469Y-197192D01*
X339535Y-196861D01*
X340045D01*
X340078Y-197028D01*
X340476Y-197624D01*
X341071Y-198022D01*
X341774Y-198161D01*
X342476Y-198022D01*
X343071Y-197624D01*
X343469Y-197028D01*
X343609Y-196326D01*
X343469Y-195624D01*
X343071Y-195028D01*
X342476Y-194631D01*
X341774Y-194491D01*
D02*
G37*
G36*
X309055Y-193834D02*
X308353Y-193974D01*
X307757Y-194372D01*
X307360Y-194967D01*
X307220Y-195669D01*
X307360Y-196372D01*
X307480Y-196552D01*
X307179Y-197002D01*
X307087Y-196984D01*
X306384Y-197123D01*
X305789Y-197521D01*
X305391Y-198117D01*
X305251Y-198819D01*
X305391Y-199521D01*
X305789Y-200117D01*
X306384Y-200515D01*
X307087Y-200654D01*
X307789Y-200515D01*
X308384Y-200117D01*
X308782Y-199521D01*
X308922Y-198819D01*
X308782Y-198117D01*
X308662Y-197936D01*
X308962Y-197486D01*
X309055Y-197504D01*
X309757Y-197365D01*
X310353Y-196967D01*
X310751Y-196372D01*
X310890Y-195669D01*
X310751Y-194967D01*
X310353Y-194372D01*
X309757Y-193974D01*
X309055Y-193834D01*
D02*
G37*
G36*
X331220Y-194431D02*
X330518Y-194571D01*
X329922Y-194969D01*
X329525Y-195564D01*
X329385Y-196266D01*
X329525Y-196969D01*
X329922Y-197564D01*
X330518Y-197962D01*
X331220Y-198102D01*
X331923Y-197962D01*
X332518Y-197564D01*
X332916Y-196969D01*
X333055Y-196266D01*
X332916Y-195564D01*
X332518Y-194969D01*
X331923Y-194571D01*
X331220Y-194431D01*
D02*
G37*
G36*
X389567Y-194604D02*
X388865Y-194744D01*
X388269Y-195142D01*
X387872Y-195737D01*
X387732Y-196440D01*
X387872Y-197142D01*
X388269Y-197737D01*
X388865Y-198135D01*
X389567Y-198275D01*
X390269Y-198135D01*
X390865Y-197737D01*
X391263Y-197142D01*
X391403Y-196440D01*
X391263Y-195737D01*
X390865Y-195142D01*
X390269Y-194744D01*
X389567Y-194604D01*
D02*
G37*
G36*
X380363Y-194905D02*
X379661Y-195045D01*
X379066Y-195442D01*
X378668Y-196038D01*
X378528Y-196740D01*
X378668Y-197442D01*
X379066Y-198038D01*
X379661Y-198436D01*
X380363Y-198575D01*
X381066Y-198436D01*
X381661Y-198038D01*
X382059Y-197442D01*
X382199Y-196740D01*
X382059Y-196038D01*
X381661Y-195442D01*
X381066Y-195045D01*
X380363Y-194905D01*
D02*
G37*
G36*
X291831Y-195177D02*
X291128Y-195317D01*
X290533Y-195715D01*
X290135Y-196310D01*
X289995Y-197012D01*
X290135Y-197715D01*
X290533Y-198310D01*
X291128Y-198708D01*
X291831Y-198848D01*
X292533Y-198708D01*
X293128Y-198310D01*
X293526Y-197715D01*
X293666Y-197012D01*
X293526Y-196310D01*
X293128Y-195715D01*
X292533Y-195317D01*
X291831Y-195177D01*
D02*
G37*
G36*
X481496Y-195409D02*
X480794Y-195548D01*
X480198Y-195946D01*
X479801Y-196542D01*
X479661Y-197244D01*
X479801Y-197946D01*
X480198Y-198542D01*
X480794Y-198940D01*
X481496Y-199079D01*
X482198Y-198940D01*
X482794Y-198542D01*
X483192Y-197946D01*
X483331Y-197244D01*
X483192Y-196542D01*
X482794Y-195946D01*
X482198Y-195548D01*
X481496Y-195409D01*
D02*
G37*
G36*
X362598D02*
X361896Y-195548D01*
X361301Y-195946D01*
X360903Y-196542D01*
X360763Y-197244D01*
X360903Y-197946D01*
X361301Y-198542D01*
X361896Y-198940D01*
X362598Y-199079D01*
X363301Y-198940D01*
X363896Y-198542D01*
X364294Y-197946D01*
X364434Y-197244D01*
X364294Y-196542D01*
X363896Y-195946D01*
X363301Y-195548D01*
X362598Y-195409D01*
D02*
G37*
G36*
X394193Y-195835D02*
X393491Y-195975D01*
X392896Y-196373D01*
X392498Y-196968D01*
X392358Y-197670D01*
X392498Y-198373D01*
X392896Y-198968D01*
X393491Y-199366D01*
X394193Y-199506D01*
X394896Y-199366D01*
X395491Y-198968D01*
X395889Y-198373D01*
X396028Y-197670D01*
X395889Y-196968D01*
X395491Y-196373D01*
X394896Y-195975D01*
X394193Y-195835D01*
D02*
G37*
G36*
X375698Y-195865D02*
X374996Y-196004D01*
X374400Y-196402D01*
X374002Y-196998D01*
X373863Y-197700D01*
X374002Y-198402D01*
X374400Y-198998D01*
X374996Y-199396D01*
X375698Y-199535D01*
X376400Y-199396D01*
X376996Y-198998D01*
X377394Y-198402D01*
X377533Y-197700D01*
X377394Y-196998D01*
X376996Y-196402D01*
X376400Y-196004D01*
X375698Y-195865D01*
D02*
G37*
G36*
X521654Y-196984D02*
X520951Y-197123D01*
X520356Y-197521D01*
X519958Y-198117D01*
X519818Y-198819D01*
X519958Y-199521D01*
X520356Y-200117D01*
X520951Y-200515D01*
X521654Y-200654D01*
X522356Y-200515D01*
X522951Y-200117D01*
X523349Y-199521D01*
X523489Y-198819D01*
X523349Y-198117D01*
X522951Y-197521D01*
X522356Y-197123D01*
X521654Y-196984D01*
D02*
G37*
G36*
X314675D02*
X313973Y-197123D01*
X313377Y-197521D01*
X312979Y-198117D01*
X312840Y-198819D01*
X312979Y-199521D01*
X313377Y-200117D01*
X313973Y-200515D01*
X314675Y-200654D01*
X315377Y-200515D01*
X315973Y-200117D01*
X316371Y-199521D01*
X316510Y-198819D01*
X316371Y-198117D01*
X315973Y-197521D01*
X315377Y-197123D01*
X314675Y-196984D01*
D02*
G37*
G36*
X513386Y-197377D02*
X512683Y-197517D01*
X512088Y-197915D01*
X511690Y-198510D01*
X511551Y-199213D01*
X511690Y-199915D01*
X512088Y-200510D01*
X512683Y-200908D01*
X513386Y-201048D01*
X514088Y-200908D01*
X514684Y-200510D01*
X515081Y-199915D01*
X515221Y-199213D01*
X515081Y-198510D01*
X514684Y-197915D01*
X514088Y-197517D01*
X513386Y-197377D01*
D02*
G37*
G36*
X275590Y-197771D02*
X274888Y-197911D01*
X274293Y-198309D01*
X273895Y-198904D01*
X273755Y-199606D01*
X273895Y-200309D01*
X274293Y-200904D01*
X274888Y-201302D01*
X275590Y-201442D01*
X276293Y-201302D01*
X276888Y-200904D01*
X277286Y-200309D01*
X277426Y-199606D01*
X277286Y-198904D01*
X276888Y-198309D01*
X276293Y-197911D01*
X275590Y-197771D01*
D02*
G37*
G36*
X343701Y-198558D02*
X342999Y-198698D01*
X342403Y-199096D01*
X342005Y-199691D01*
X341865Y-200394D01*
X342005Y-201096D01*
X342403Y-201691D01*
X342999Y-202089D01*
X343701Y-202229D01*
X344403Y-202089D01*
X344999Y-201691D01*
X345396Y-201096D01*
X345536Y-200394D01*
X345396Y-199691D01*
X344999Y-199096D01*
X344403Y-198698D01*
X343701Y-198558D01*
D02*
G37*
G36*
X289370D02*
X288668Y-198698D01*
X288072Y-199096D01*
X287674Y-199691D01*
X287535Y-200394D01*
X287674Y-201096D01*
X288072Y-201691D01*
X288668Y-202089D01*
X289370Y-202229D01*
X290072Y-202089D01*
X290668Y-201691D01*
X291066Y-201096D01*
X291205Y-200394D01*
X291066Y-199691D01*
X290668Y-199096D01*
X290072Y-198698D01*
X289370Y-198558D01*
D02*
G37*
G36*
X261024D02*
X260321Y-198698D01*
X259726Y-199096D01*
X259328Y-199691D01*
X259188Y-200394D01*
X259328Y-201096D01*
X259726Y-201691D01*
X260321Y-202089D01*
X261024Y-202229D01*
X261726Y-202089D01*
X262321Y-201691D01*
X262719Y-201096D01*
X262859Y-200394D01*
X262719Y-199691D01*
X262321Y-199096D01*
X261726Y-198698D01*
X261024Y-198558D01*
D02*
G37*
G36*
X589370Y-199740D02*
X588668Y-199879D01*
X588072Y-200277D01*
X587675Y-200872D01*
X587535Y-201575D01*
X587675Y-202277D01*
X588072Y-202872D01*
X588668Y-203270D01*
X589370Y-203410D01*
X590072Y-203270D01*
X590668Y-202872D01*
X591066Y-202277D01*
X591205Y-201575D01*
X591066Y-200872D01*
X590668Y-200277D01*
X590072Y-199879D01*
X589370Y-199740D01*
D02*
G37*
G36*
X385541Y-200625D02*
X384839Y-200765D01*
X384243Y-201163D01*
X383845Y-201758D01*
X383706Y-202460D01*
X383845Y-203163D01*
X384243Y-203758D01*
X384839Y-204156D01*
X385541Y-204295D01*
X386243Y-204156D01*
X386839Y-203758D01*
X387237Y-203163D01*
X387376Y-202460D01*
X387237Y-201758D01*
X386839Y-201163D01*
X386243Y-200765D01*
X385541Y-200625D01*
D02*
G37*
G36*
X347638Y-200921D02*
X346936Y-201060D01*
X346340Y-201458D01*
X345942Y-202054D01*
X345802Y-202756D01*
X345942Y-203458D01*
X346340Y-204054D01*
X346936Y-204451D01*
X347638Y-204591D01*
X348340Y-204451D01*
X348936Y-204054D01*
X349333Y-203458D01*
X349473Y-202756D01*
X349333Y-202054D01*
X348936Y-201458D01*
X348340Y-201060D01*
X347638Y-200921D01*
D02*
G37*
G36*
X373730Y-201053D02*
X373028Y-201193D01*
X372432Y-201591D01*
X372035Y-202186D01*
X371895Y-202888D01*
X372035Y-203591D01*
X372432Y-204186D01*
X373028Y-204584D01*
X373730Y-204724D01*
X374432Y-204584D01*
X375028Y-204186D01*
X375426Y-203591D01*
X375565Y-202888D01*
X375426Y-202186D01*
X375028Y-201591D01*
X374432Y-201193D01*
X373730Y-201053D01*
D02*
G37*
G36*
X289370Y-204070D02*
X288668Y-204210D01*
X288072Y-204608D01*
X287674Y-205203D01*
X287535Y-205906D01*
X287674Y-206608D01*
X288072Y-207203D01*
X288668Y-207601D01*
X289370Y-207741D01*
X290072Y-207601D01*
X290668Y-207203D01*
X291066Y-206608D01*
X291205Y-205906D01*
X291066Y-205203D01*
X290668Y-204608D01*
X290072Y-204210D01*
X289370Y-204070D01*
D02*
G37*
G36*
X383572Y-204369D02*
X382870Y-204509D01*
X382274Y-204907D01*
X381876Y-205502D01*
X381737Y-206205D01*
X381876Y-206907D01*
X382274Y-207502D01*
X382870Y-207900D01*
X383572Y-208040D01*
X384274Y-207900D01*
X384870Y-207502D01*
X385268Y-206907D01*
X385407Y-206205D01*
X385268Y-205502D01*
X384870Y-204907D01*
X384274Y-204509D01*
X383572Y-204369D01*
D02*
G37*
G36*
X424409Y-203677D02*
X423707Y-203816D01*
X423112Y-204214D01*
X422714Y-204809D01*
X422574Y-205512D01*
X422714Y-206214D01*
X423112Y-206809D01*
X423707Y-207207D01*
X424409Y-207347D01*
X425112Y-207207D01*
X425707Y-206809D01*
X425709Y-206807D01*
X426239Y-206913D01*
X426257Y-207001D01*
X426655Y-207597D01*
X427250Y-207995D01*
X427953Y-208135D01*
X428655Y-207995D01*
X429250Y-207597D01*
X429648Y-207001D01*
X429788Y-206299D01*
X429648Y-205597D01*
X429250Y-205001D01*
X428655Y-204604D01*
X427953Y-204464D01*
X427250Y-204604D01*
X426655Y-205001D01*
X426653Y-205004D01*
X426123Y-204898D01*
X426105Y-204809D01*
X425707Y-204214D01*
X425112Y-203816D01*
X424409Y-203677D01*
D02*
G37*
G36*
X588922Y-204627D02*
X588220Y-204766D01*
X587625Y-205164D01*
X587227Y-205760D01*
X587087Y-206462D01*
X587227Y-207164D01*
X587625Y-207760D01*
X588220Y-208157D01*
X588922Y-208297D01*
X589625Y-208157D01*
X590220Y-207760D01*
X590618Y-207164D01*
X590758Y-206462D01*
X590618Y-205760D01*
X590220Y-205164D01*
X589625Y-204766D01*
X588922Y-204627D01*
D02*
G37*
G36*
X343701Y-207614D02*
X342999Y-207753D01*
X342403Y-208151D01*
X342005Y-208747D01*
X341865Y-209449D01*
X342005Y-210151D01*
X342403Y-210747D01*
X342999Y-211144D01*
X343701Y-211284D01*
X344403Y-211144D01*
X344999Y-210747D01*
X345396Y-210151D01*
X345536Y-209449D01*
X345396Y-208747D01*
X344999Y-208151D01*
X344403Y-207753D01*
X343701Y-207614D01*
D02*
G37*
G36*
X309449Y-209976D02*
X308747Y-210116D01*
X308151Y-210513D01*
X307753Y-211109D01*
X307614Y-211811D01*
X307753Y-212513D01*
X308151Y-213109D01*
X308747Y-213507D01*
X309449Y-213646D01*
X310151Y-213507D01*
X310747Y-213109D01*
X311076Y-212615D01*
X311575Y-212719D01*
X311690Y-213301D01*
X312088Y-213896D01*
X312684Y-214294D01*
X313386Y-214434D01*
X314088Y-214294D01*
X314684Y-213896D01*
X315081Y-213301D01*
X315221Y-212598D01*
X315081Y-211896D01*
X314684Y-211301D01*
X314088Y-210903D01*
X313386Y-210763D01*
X312684Y-210903D01*
X312088Y-211301D01*
X311758Y-211794D01*
X311260Y-211691D01*
X311144Y-211109D01*
X310747Y-210513D01*
X310151Y-210116D01*
X309449Y-209976D01*
D02*
G37*
G36*
X589370Y-211157D02*
X588668Y-211297D01*
X588072Y-211694D01*
X587675Y-212290D01*
X587535Y-212992D01*
X587675Y-213695D01*
X588072Y-214290D01*
X588668Y-214688D01*
X589370Y-214827D01*
X590072Y-214688D01*
X590668Y-214290D01*
X591066Y-213695D01*
X591205Y-212992D01*
X591066Y-212290D01*
X590668Y-211694D01*
X590072Y-211297D01*
X589370Y-211157D01*
D02*
G37*
G36*
X-3528Y-205543D02*
X-13402D01*
Y-215417D01*
X-3528D01*
Y-205543D01*
D02*
G37*
G36*
X579134Y-212171D02*
X578432Y-212310D01*
X577836Y-212708D01*
X577438Y-213304D01*
X577299Y-214006D01*
X577438Y-214708D01*
X577836Y-215304D01*
X578432Y-215702D01*
X579134Y-215841D01*
X579836Y-215702D01*
X580432Y-215304D01*
X580829Y-214708D01*
X580969Y-214006D01*
X580829Y-213304D01*
X580432Y-212708D01*
X579836Y-212310D01*
X579134Y-212171D01*
D02*
G37*
G36*
X357480Y-212732D02*
X356778Y-212871D01*
X356183Y-213269D01*
X355785Y-213865D01*
X355645Y-214567D01*
X355785Y-215269D01*
X356183Y-215865D01*
X356778Y-216263D01*
X357480Y-216402D01*
X358183Y-216263D01*
X358778Y-215865D01*
X359176Y-215269D01*
X359316Y-214567D01*
X359176Y-213865D01*
X358778Y-213269D01*
X358183Y-212871D01*
X357480Y-212732D01*
D02*
G37*
G36*
X261082Y-213839D02*
X260269Y-214000D01*
X259580Y-214461D01*
X259120Y-215150D01*
X258958Y-215962D01*
X259120Y-216775D01*
X259580Y-217464D01*
X260269Y-217925D01*
X261082Y-218086D01*
X261894Y-217925D01*
X262584Y-217464D01*
X263044Y-216775D01*
X263206Y-215962D01*
X263044Y-215150D01*
X262584Y-214461D01*
X261894Y-214000D01*
X261082Y-213839D01*
D02*
G37*
G36*
X448573Y-213848D02*
X447760Y-214010D01*
X447071Y-214470D01*
X446611Y-215159D01*
X446449Y-215972D01*
X446611Y-216785D01*
X447071Y-217474D01*
X447760Y-217934D01*
X448573Y-218096D01*
X449385Y-217934D01*
X450074Y-217474D01*
X450535Y-216785D01*
X450697Y-215972D01*
X450535Y-215159D01*
X450074Y-214470D01*
X449385Y-214010D01*
X448573Y-213848D01*
D02*
G37*
G36*
X488189Y-214700D02*
X487487Y-214840D01*
X486891Y-215238D01*
X486493Y-215833D01*
X486354Y-216535D01*
X486493Y-217238D01*
X486891Y-217833D01*
X487487Y-218231D01*
X488189Y-218371D01*
X488891Y-218231D01*
X489487Y-217833D01*
X489885Y-217238D01*
X490024Y-216535D01*
X489885Y-215833D01*
X489487Y-215238D01*
X488891Y-214840D01*
X488189Y-214700D01*
D02*
G37*
G36*
X407874D02*
X407172Y-214840D01*
X406576Y-215238D01*
X406179Y-215833D01*
X406039Y-216535D01*
X406179Y-217238D01*
X406576Y-217833D01*
X407172Y-218231D01*
X407874Y-218371D01*
X408576Y-218231D01*
X409172Y-217833D01*
X409570Y-217238D01*
X409709Y-216535D01*
X409570Y-215833D01*
X409172Y-215238D01*
X408576Y-214840D01*
X407874Y-214700D01*
D02*
G37*
G36*
X390158Y-215881D02*
X389455Y-216021D01*
X388860Y-216419D01*
X388462Y-217014D01*
X388322Y-217717D01*
X388462Y-218419D01*
X388860Y-219014D01*
X389455Y-219412D01*
X390158Y-219552D01*
X390860Y-219412D01*
X391455Y-219014D01*
X391853Y-218419D01*
X391993Y-217717D01*
X391853Y-217014D01*
X391455Y-216419D01*
X390860Y-216021D01*
X390158Y-215881D01*
D02*
G37*
G36*
X368232D02*
X367529Y-216021D01*
X366934Y-216419D01*
X366536Y-217014D01*
X366396Y-217717D01*
X366536Y-218419D01*
X366934Y-219014D01*
X367529Y-219412D01*
X368232Y-219552D01*
X368934Y-219412D01*
X369530Y-219014D01*
X369927Y-218419D01*
X370067Y-217717D01*
X369927Y-217014D01*
X369530Y-216419D01*
X368934Y-216021D01*
X368232Y-215881D01*
D02*
G37*
G36*
X404626Y-217850D02*
X403924Y-217989D01*
X403328Y-218387D01*
X402930Y-218983D01*
X402791Y-219685D01*
X402930Y-220387D01*
X403328Y-220983D01*
X403924Y-221381D01*
X404626Y-221520D01*
X405328Y-221381D01*
X405924Y-220983D01*
X406321Y-220387D01*
X406461Y-219685D01*
X406321Y-218983D01*
X405924Y-218387D01*
X405328Y-217989D01*
X404626Y-217850D01*
D02*
G37*
G36*
X500971Y-218060D02*
X500268Y-218200D01*
X499673Y-218598D01*
X499275Y-219193D01*
X499135Y-219896D01*
X499275Y-220598D01*
X499673Y-221193D01*
X500268Y-221591D01*
X500971Y-221731D01*
X501673Y-221591D01*
X502268Y-221193D01*
X502666Y-220598D01*
X502806Y-219896D01*
X502666Y-219193D01*
X502268Y-218598D01*
X501673Y-218200D01*
X500971Y-218060D01*
D02*
G37*
G36*
X590188Y-219326D02*
X589486Y-219466D01*
X588890Y-219864D01*
X588493Y-220459D01*
X588353Y-221161D01*
X588493Y-221864D01*
X588890Y-222459D01*
X589486Y-222857D01*
X590188Y-222997D01*
X590890Y-222857D01*
X591486Y-222459D01*
X591884Y-221864D01*
X592023Y-221161D01*
X591884Y-220459D01*
X591486Y-219864D01*
X590890Y-219466D01*
X590188Y-219326D01*
D02*
G37*
G36*
X608661Y-218637D02*
X607959Y-218777D01*
X607364Y-219175D01*
X606966Y-219770D01*
X606826Y-220472D01*
X606966Y-221175D01*
X607364Y-221770D01*
X607959Y-222168D01*
X608661Y-222308D01*
X609364Y-222168D01*
X609613Y-222001D01*
X610103Y-221963D01*
X610235Y-222141D01*
X610513Y-222558D01*
X611109Y-222955D01*
X611811Y-223095D01*
X612513Y-222955D01*
X613109Y-222558D01*
X613507Y-221962D01*
X613646Y-221260D01*
X613507Y-220557D01*
X613109Y-219962D01*
X612513Y-219564D01*
X611811Y-219425D01*
X611109Y-219564D01*
X610859Y-219731D01*
X610370Y-219769D01*
X610237Y-219591D01*
X609959Y-219175D01*
X609364Y-218777D01*
X608661Y-218637D01*
D02*
G37*
G36*
X375197Y-219425D02*
X374495Y-219564D01*
X373899Y-219962D01*
X373501Y-220557D01*
X373362Y-221260D01*
X373501Y-221962D01*
X373899Y-222558D01*
X374495Y-222955D01*
X375197Y-223095D01*
X375899Y-222955D01*
X376495Y-222558D01*
X376892Y-221962D01*
X377032Y-221260D01*
X376892Y-220557D01*
X376495Y-219962D01*
X375899Y-219564D01*
X375197Y-219425D01*
D02*
G37*
G36*
X382776Y-219720D02*
X382073Y-219860D01*
X381478Y-220257D01*
X381080Y-220853D01*
X380940Y-221555D01*
X381080Y-222257D01*
X381478Y-222853D01*
X382073Y-223251D01*
X382776Y-223390D01*
X383478Y-223251D01*
X384073Y-222853D01*
X384471Y-222257D01*
X384611Y-221555D01*
X384471Y-220853D01*
X384073Y-220257D01*
X383478Y-219860D01*
X382776Y-219720D01*
D02*
G37*
G36*
X430020Y-215175D02*
X429318Y-215315D01*
X428722Y-215713D01*
X428324Y-216308D01*
X428185Y-217010D01*
X428324Y-217713D01*
X428513Y-217995D01*
X428324Y-218277D01*
X428185Y-218979D01*
X428324Y-219681D01*
X428513Y-219963D01*
X428324Y-220245D01*
X428185Y-220948D01*
X428324Y-221650D01*
X428513Y-221932D01*
X428324Y-222214D01*
X428185Y-222916D01*
X428324Y-223618D01*
X428722Y-224214D01*
X429318Y-224612D01*
X430020Y-224751D01*
X430722Y-224612D01*
X431318Y-224214D01*
X431715Y-223618D01*
X431855Y-222916D01*
X431715Y-222214D01*
X431527Y-221932D01*
X431715Y-221650D01*
X431855Y-220948D01*
X431715Y-220245D01*
X431527Y-219963D01*
X431715Y-219681D01*
X431855Y-218979D01*
X431715Y-218277D01*
X431527Y-217995D01*
X431715Y-217713D01*
X431855Y-217010D01*
X431715Y-216308D01*
X431318Y-215713D01*
X430722Y-215315D01*
X430020Y-215175D01*
D02*
G37*
G36*
X472047Y-215488D02*
X471345Y-215627D01*
X470750Y-216025D01*
X470352Y-216620D01*
X470212Y-217323D01*
X470352Y-218025D01*
X470540Y-218307D01*
X470352Y-218589D01*
X470212Y-219291D01*
X470352Y-219994D01*
X470540Y-220276D01*
X470352Y-220557D01*
X470212Y-221260D01*
X470352Y-221962D01*
X470540Y-222244D01*
X470352Y-222526D01*
X470212Y-223228D01*
X470352Y-223931D01*
X470750Y-224526D01*
X471345Y-224924D01*
X472047Y-225064D01*
X472750Y-224924D01*
X473345Y-224526D01*
X473743Y-223931D01*
X473882Y-223228D01*
X473743Y-222526D01*
X473554Y-222244D01*
X473743Y-221962D01*
X473882Y-221260D01*
X473743Y-220557D01*
X473554Y-220276D01*
X473743Y-219994D01*
X473882Y-219291D01*
X473743Y-218589D01*
X473554Y-218307D01*
X473743Y-218025D01*
X473882Y-217323D01*
X473743Y-216620D01*
X473345Y-216025D01*
X472750Y-215627D01*
X472047Y-215488D01*
D02*
G37*
G36*
X404493Y-222314D02*
X403790Y-222453D01*
X403195Y-222851D01*
X402797Y-223447D01*
X402658Y-224149D01*
X402797Y-224851D01*
X403195Y-225447D01*
X403790Y-225845D01*
X404493Y-225984D01*
X405195Y-225845D01*
X405790Y-225447D01*
X406188Y-224851D01*
X406328Y-224149D01*
X406188Y-223447D01*
X405790Y-222851D01*
X405195Y-222453D01*
X404493Y-222314D01*
D02*
G37*
G36*
X584646Y-223362D02*
X583943Y-223501D01*
X583348Y-223899D01*
X582950Y-224495D01*
X582810Y-225197D01*
X582950Y-225899D01*
X583348Y-226495D01*
X583943Y-226892D01*
X584646Y-227032D01*
X585348Y-226892D01*
X585943Y-226495D01*
X586341Y-225899D01*
X586481Y-225197D01*
X586341Y-224495D01*
X585943Y-223899D01*
X585348Y-223501D01*
X584646Y-223362D01*
D02*
G37*
G36*
X542913Y-226905D02*
X542211Y-227045D01*
X541616Y-227442D01*
X541442Y-227702D01*
X540841D01*
X540668Y-227442D01*
X540072Y-227045D01*
X539370Y-226905D01*
X538668Y-227045D01*
X538072Y-227442D01*
X537675Y-228038D01*
X537535Y-228740D01*
X537675Y-229443D01*
X538072Y-230038D01*
X538668Y-230436D01*
X539370Y-230575D01*
X540072Y-230436D01*
X540668Y-230038D01*
X540841Y-229779D01*
X541442D01*
X541616Y-230038D01*
X542211Y-230436D01*
X542913Y-230575D01*
X543616Y-230436D01*
X544211Y-230038D01*
X544609Y-229443D01*
X544749Y-228740D01*
X544609Y-228038D01*
X544211Y-227442D01*
X543616Y-227045D01*
X542913Y-226905D01*
D02*
G37*
G36*
X616929Y-224149D02*
X616227Y-224289D01*
X615631Y-224687D01*
X615234Y-225282D01*
X615094Y-225984D01*
X615234Y-226687D01*
X615631Y-227282D01*
X616227Y-227680D01*
X616929Y-227819D01*
X617631Y-227680D01*
X618227Y-227282D01*
X618625Y-226687D01*
X618764Y-225984D01*
X618625Y-225282D01*
X618227Y-224687D01*
X617631Y-224289D01*
X616929Y-224149D01*
D02*
G37*
G36*
X280315Y-224543D02*
X279613Y-224682D01*
X279017Y-225080D01*
X278619Y-225676D01*
X278480Y-226378D01*
X278619Y-227080D01*
X279017Y-227676D01*
X279489Y-227991D01*
X279613Y-228074D01*
X279497Y-228552D01*
X279353Y-228523D01*
X279134Y-228480D01*
X278432Y-228619D01*
X277836Y-229017D01*
X277438Y-229613D01*
X277299Y-230315D01*
X277438Y-231017D01*
X277836Y-231613D01*
X278432Y-232011D01*
X279134Y-232150D01*
X279836Y-232011D01*
X280432Y-231613D01*
X280829Y-231017D01*
X280969Y-230315D01*
X280829Y-229613D01*
X280432Y-229017D01*
X279960Y-228702D01*
X279836Y-228619D01*
X279952Y-228141D01*
X280095Y-228169D01*
X280315Y-228213D01*
X281017Y-228074D01*
X281613Y-227676D01*
X282011Y-227080D01*
X282150Y-226378D01*
X282011Y-225676D01*
X281613Y-225080D01*
X281017Y-224682D01*
X280315Y-224543D01*
D02*
G37*
G36*
X626987Y-226511D02*
X626285Y-226651D01*
X625690Y-227049D01*
X625292Y-227644D01*
X625152Y-228346D01*
X625292Y-229049D01*
X625690Y-229644D01*
X626285Y-230042D01*
X626987Y-230182D01*
X627690Y-230042D01*
X628285Y-229644D01*
X628683Y-229049D01*
X628823Y-228346D01*
X628683Y-227644D01*
X628285Y-227049D01*
X627690Y-226651D01*
X626987Y-226511D01*
D02*
G37*
G36*
X329134Y-226905D02*
X328432Y-227045D01*
X327836Y-227442D01*
X327438Y-228038D01*
X327299Y-228740D01*
X327438Y-229443D01*
X327836Y-230038D01*
X328432Y-230436D01*
X329134Y-230575D01*
X329836Y-230436D01*
X330432Y-230038D01*
X330829Y-229443D01*
X330969Y-228740D01*
X330829Y-228038D01*
X330432Y-227442D01*
X329836Y-227045D01*
X329134Y-226905D01*
D02*
G37*
G36*
X429528Y-229661D02*
X428825Y-229801D01*
X428230Y-230198D01*
X427832Y-230794D01*
X427692Y-231496D01*
X427832Y-232198D01*
X428230Y-232794D01*
X428825Y-233192D01*
X429528Y-233331D01*
X430230Y-233192D01*
X430825Y-232794D01*
X431223Y-232198D01*
X431363Y-231496D01*
X431223Y-230794D01*
X430825Y-230198D01*
X430230Y-229801D01*
X429528Y-229661D01*
D02*
G37*
G36*
X321654Y-230842D02*
X320951Y-230982D01*
X320356Y-231379D01*
X319958Y-231975D01*
X319818Y-232677D01*
X319958Y-233380D01*
X320356Y-233975D01*
X320951Y-234373D01*
X321654Y-234512D01*
X322356Y-234373D01*
X322951Y-233975D01*
X323349Y-233380D01*
X323489Y-232677D01*
X323349Y-231975D01*
X322951Y-231379D01*
X322356Y-230982D01*
X321654Y-230842D01*
D02*
G37*
G36*
X373093Y-231137D02*
X372391Y-231277D01*
X371796Y-231675D01*
X371398Y-232270D01*
X371258Y-232972D01*
X371398Y-233675D01*
X371796Y-234270D01*
X372391Y-234668D01*
X373093Y-234808D01*
X373796Y-234668D01*
X374391Y-234270D01*
X374789Y-233675D01*
X374929Y-232972D01*
X374789Y-232270D01*
X374391Y-231675D01*
X373796Y-231277D01*
X373093Y-231137D01*
D02*
G37*
G36*
X10007Y-233133D02*
X9305Y-233272D01*
X8710Y-233670D01*
X8312Y-234265D01*
X8172Y-234968D01*
X8312Y-235670D01*
X8710Y-236265D01*
X9305Y-236663D01*
X10007Y-236803D01*
X10710Y-236663D01*
X11305Y-236265D01*
X11703Y-235670D01*
X11843Y-234968D01*
X11703Y-234265D01*
X11305Y-233670D01*
X10710Y-233272D01*
X10007Y-233133D01*
D02*
G37*
G36*
X288D02*
X-414Y-233272D01*
X-1010Y-233670D01*
X-1407Y-234265D01*
X-1547Y-234968D01*
X-1407Y-235670D01*
X-1010Y-236265D01*
X-414Y-236663D01*
X288Y-236803D01*
X990Y-236663D01*
X1586Y-236265D01*
X1984Y-235670D01*
X2123Y-234968D01*
X1984Y-234265D01*
X1586Y-233670D01*
X990Y-233272D01*
X288Y-233133D01*
D02*
G37*
G36*
X230251Y-230431D02*
X229548Y-230571D01*
X228953Y-230969D01*
X228555Y-231564D01*
X228415Y-232266D01*
X228555Y-232969D01*
X228953Y-233564D01*
X228735Y-234020D01*
X228469Y-234417D01*
X228329Y-235119D01*
X228469Y-235822D01*
X228867Y-236417D01*
X229462Y-236815D01*
X230165Y-236954D01*
X230867Y-236815D01*
X231463Y-236417D01*
X231860Y-235822D01*
X232000Y-235119D01*
X231860Y-234417D01*
X231463Y-233822D01*
X231681Y-233366D01*
X231946Y-232969D01*
X232086Y-232266D01*
X231946Y-231564D01*
X231548Y-230969D01*
X230953Y-230571D01*
X230251Y-230431D01*
D02*
G37*
G36*
X340786Y-233992D02*
X340083Y-234131D01*
X339488Y-234529D01*
X339090Y-235124D01*
X338950Y-235827D01*
X339090Y-236529D01*
X339488Y-237124D01*
X340083Y-237522D01*
X340786Y-237662D01*
X341488Y-237522D01*
X342083Y-237124D01*
X342481Y-236529D01*
X342621Y-235827D01*
X342481Y-235124D01*
X342083Y-234529D01*
X341488Y-234131D01*
X340786Y-233992D01*
D02*
G37*
G36*
X581890Y-234090D02*
X581187Y-234230D01*
X580592Y-234628D01*
X580194Y-235223D01*
X580055Y-235925D01*
X580194Y-236628D01*
X580592Y-237223D01*
X581187Y-237621D01*
X581890Y-237760D01*
X582592Y-237621D01*
X583187Y-237223D01*
X583585Y-236628D01*
X583725Y-235925D01*
X583585Y-235223D01*
X583187Y-234628D01*
X582592Y-234230D01*
X581890Y-234090D01*
D02*
G37*
G36*
X312322Y-234385D02*
X311620Y-234525D01*
X311024Y-234923D01*
X310627Y-235518D01*
X310487Y-236221D01*
X310627Y-236923D01*
X311024Y-237518D01*
X311620Y-237916D01*
X312322Y-238056D01*
X313024Y-237916D01*
X313620Y-237518D01*
X314018Y-236923D01*
X314158Y-236221D01*
X314018Y-235518D01*
X313620Y-234923D01*
X313024Y-234525D01*
X312322Y-234385D01*
D02*
G37*
G36*
X277165D02*
X276463Y-234525D01*
X275868Y-234923D01*
X275470Y-235518D01*
X275330Y-236221D01*
X275470Y-236923D01*
X275868Y-237518D01*
X276463Y-237916D01*
X277165Y-238056D01*
X277868Y-237916D01*
X278463Y-237518D01*
X278861Y-236923D01*
X279001Y-236221D01*
X278861Y-235518D01*
X278463Y-234923D01*
X277868Y-234525D01*
X277165Y-234385D01*
D02*
G37*
G36*
X293307Y-235173D02*
X292605Y-235312D01*
X292009Y-235710D01*
X291612Y-236305D01*
X291472Y-237008D01*
X291612Y-237710D01*
X292009Y-238306D01*
X292605Y-238703D01*
X293307Y-238843D01*
X294009Y-238703D01*
X294605Y-238306D01*
X295003Y-237710D01*
X295142Y-237008D01*
X295003Y-236305D01*
X294605Y-235710D01*
X294009Y-235312D01*
X293307Y-235173D01*
D02*
G37*
G36*
X288583Y-235566D02*
X287880Y-235706D01*
X287285Y-236104D01*
X286887Y-236699D01*
X286747Y-237402D01*
X286887Y-238104D01*
X287285Y-238699D01*
X287880Y-239097D01*
X288583Y-239237D01*
X289285Y-239097D01*
X289880Y-238699D01*
X290278Y-238104D01*
X290418Y-237402D01*
X290278Y-236699D01*
X289880Y-236104D01*
X289285Y-235706D01*
X288583Y-235566D01*
D02*
G37*
G36*
X281496D02*
X280794Y-235706D01*
X280198Y-236104D01*
X279801Y-236699D01*
X279661Y-237402D01*
X279801Y-238104D01*
X280198Y-238699D01*
X280794Y-239097D01*
X281496Y-239237D01*
X282198Y-239097D01*
X282794Y-238699D01*
X283192Y-238104D01*
X283331Y-237402D01*
X283192Y-236699D01*
X282794Y-236104D01*
X282198Y-235706D01*
X281496Y-235566D01*
D02*
G37*
G36*
X36614Y-230842D02*
X35912Y-230982D01*
X35316Y-231379D01*
X34919Y-231975D01*
X34779Y-232677D01*
X34919Y-233380D01*
X35087Y-233632D01*
X34923Y-233742D01*
X34525Y-234337D01*
X34385Y-235039D01*
X34511Y-235671D01*
X34337Y-235706D01*
X33742Y-236104D01*
X33344Y-236699D01*
X33204Y-237402D01*
X33344Y-238104D01*
X33742Y-238699D01*
X34337Y-239097D01*
X35039Y-239237D01*
X35742Y-239097D01*
X36337Y-238699D01*
X36735Y-238104D01*
X36875Y-237402D01*
X36749Y-236770D01*
X36923Y-236735D01*
X37518Y-236337D01*
X37916Y-235742D01*
X38056Y-235039D01*
X37916Y-234337D01*
X37747Y-234085D01*
X37912Y-233975D01*
X38310Y-233380D01*
X38449Y-232677D01*
X38310Y-231975D01*
X37912Y-231379D01*
X37317Y-230982D01*
X36614Y-230842D01*
D02*
G37*
G36*
X14665Y-235566D02*
X13963Y-235706D01*
X13368Y-236104D01*
X12970Y-236699D01*
X12830Y-237402D01*
X12970Y-238104D01*
X13368Y-238699D01*
X13963Y-239097D01*
X14665Y-239237D01*
X15368Y-239097D01*
X15963Y-238699D01*
X16361Y-238104D01*
X16501Y-237402D01*
X16361Y-236699D01*
X15963Y-236104D01*
X15368Y-235706D01*
X14665Y-235566D01*
D02*
G37*
G36*
X408760Y-236354D02*
X408057Y-236493D01*
X407462Y-236891D01*
X407064Y-237487D01*
X406925Y-238189D01*
X407064Y-238891D01*
X407462Y-239487D01*
X408057Y-239884D01*
X408760Y-240024D01*
X409462Y-239884D01*
X410058Y-239487D01*
X410455Y-238891D01*
X410595Y-238189D01*
X410455Y-237487D01*
X410058Y-236891D01*
X409462Y-236493D01*
X408760Y-236354D01*
D02*
G37*
G36*
X19685Y-237535D02*
X18983Y-237674D01*
X18387Y-238072D01*
X17989Y-238668D01*
X17850Y-239370D01*
X17989Y-240072D01*
X18387Y-240668D01*
X18983Y-241066D01*
X19685Y-241205D01*
X20387Y-241066D01*
X20983Y-240668D01*
X21381Y-240072D01*
X21520Y-239370D01*
X21381Y-238668D01*
X20983Y-238072D01*
X20387Y-237674D01*
X19685Y-237535D01*
D02*
G37*
G36*
X333714Y-237929D02*
X333012Y-238068D01*
X332416Y-238466D01*
X332018Y-239061D01*
X331879Y-239764D01*
X332018Y-240466D01*
X332416Y-241061D01*
X333012Y-241459D01*
X333714Y-241599D01*
X334416Y-241459D01*
X335012Y-241061D01*
X335409Y-240466D01*
X335549Y-239764D01*
X335409Y-239061D01*
X335012Y-238466D01*
X334416Y-238068D01*
X333714Y-237929D01*
D02*
G37*
G36*
X231102D02*
X230400Y-238068D01*
X229805Y-238466D01*
X229407Y-239061D01*
X229267Y-239764D01*
X229407Y-240466D01*
X229805Y-241061D01*
X230400Y-241459D01*
X231102Y-241599D01*
X231805Y-241459D01*
X232400Y-241061D01*
X232798Y-240466D01*
X232938Y-239764D01*
X232798Y-239061D01*
X232400Y-238466D01*
X231805Y-238068D01*
X231102Y-237929D01*
D02*
G37*
G36*
X204331Y-230842D02*
X203628Y-230982D01*
X203033Y-231379D01*
X202635Y-231975D01*
X202496Y-232677D01*
X202635Y-233380D01*
X202911Y-233792D01*
X203033Y-233975D01*
X202801Y-234421D01*
X202639Y-234529D01*
X202241Y-235124D01*
X202102Y-235827D01*
X202241Y-236529D01*
X202561Y-237008D01*
X202241Y-237487D01*
X202102Y-238189D01*
X202241Y-238891D01*
X202500Y-239278D01*
X202110Y-239862D01*
X201970Y-240564D01*
X202110Y-241267D01*
X202507Y-241862D01*
X203103Y-242260D01*
X203805Y-242400D01*
X204507Y-242260D01*
X205103Y-241862D01*
X205501Y-241267D01*
X205640Y-240564D01*
X205501Y-239862D01*
X205242Y-239475D01*
X205633Y-238891D01*
X205772Y-238189D01*
X205633Y-237487D01*
X205313Y-237008D01*
X205633Y-236529D01*
X205772Y-235827D01*
X205633Y-235124D01*
X205357Y-234712D01*
X205235Y-234529D01*
X205467Y-234083D01*
X205628Y-233975D01*
X206026Y-233380D01*
X206166Y-232677D01*
X206026Y-231975D01*
X205628Y-231379D01*
X205033Y-230982D01*
X204331Y-230842D01*
D02*
G37*
G36*
X-23622Y-227495D02*
X-24324Y-227635D01*
X-24920Y-228033D01*
X-25318Y-228628D01*
X-25457Y-229331D01*
X-25318Y-230033D01*
X-24920Y-230628D01*
X-24324Y-231026D01*
X-24234Y-231044D01*
Y-231554D01*
X-24324Y-231572D01*
X-24920Y-231970D01*
X-25318Y-232565D01*
X-25457Y-233268D01*
X-25318Y-233970D01*
X-24920Y-234565D01*
X-24324Y-234963D01*
X-24234Y-234981D01*
Y-235491D01*
X-24324Y-235509D01*
X-24920Y-235907D01*
X-25318Y-236502D01*
X-25457Y-237205D01*
X-25318Y-237907D01*
X-24920Y-238502D01*
X-24324Y-238900D01*
X-24234Y-238918D01*
Y-239428D01*
X-24324Y-239446D01*
X-24920Y-239844D01*
X-25318Y-240439D01*
X-25457Y-241142D01*
X-25318Y-241844D01*
X-24920Y-242439D01*
X-24324Y-242837D01*
X-23622Y-242977D01*
X-22920Y-242837D01*
X-22324Y-242439D01*
X-21926Y-241844D01*
X-21787Y-241142D01*
X-21926Y-240439D01*
X-22324Y-239844D01*
X-22920Y-239446D01*
X-23010Y-239428D01*
Y-238918D01*
X-22920Y-238900D01*
X-22324Y-238502D01*
X-21926Y-237907D01*
X-21787Y-237205D01*
X-21926Y-236502D01*
X-22324Y-235907D01*
X-22920Y-235509D01*
X-23010Y-235491D01*
Y-234981D01*
X-22920Y-234963D01*
X-22324Y-234565D01*
X-21926Y-233970D01*
X-21787Y-233268D01*
X-21926Y-232565D01*
X-22324Y-231970D01*
X-22920Y-231572D01*
X-23010Y-231554D01*
Y-231044D01*
X-22920Y-231026D01*
X-22324Y-230628D01*
X-21926Y-230033D01*
X-21787Y-229331D01*
X-21926Y-228628D01*
X-22324Y-228033D01*
X-22920Y-227635D01*
X-23622Y-227495D01*
D02*
G37*
G36*
X483831Y-239503D02*
X483129Y-239643D01*
X482534Y-240041D01*
X482136Y-240636D01*
X481996Y-241339D01*
X482136Y-242041D01*
X482534Y-242636D01*
X483129Y-243034D01*
X483831Y-243174D01*
X484534Y-243034D01*
X485129Y-242636D01*
X485527Y-242041D01*
X485666Y-241339D01*
X485527Y-240636D01*
X485129Y-240041D01*
X484534Y-239643D01*
X483831Y-239503D01*
D02*
G37*
G36*
X596063Y-238060D02*
X595361Y-238199D01*
X594765Y-238597D01*
X594367Y-239193D01*
X594228Y-239895D01*
X594367Y-240597D01*
X594600Y-240945D01*
X594367Y-241293D01*
X594228Y-241995D01*
X594367Y-242697D01*
X594765Y-243293D01*
X595361Y-243690D01*
X596063Y-243830D01*
X596765Y-243690D01*
X597361Y-243293D01*
X597759Y-242697D01*
X597898Y-241995D01*
X597759Y-241293D01*
X597526Y-240945D01*
X597759Y-240597D01*
X597898Y-239895D01*
X597759Y-239193D01*
X597361Y-238597D01*
X596765Y-238199D01*
X596063Y-238060D01*
D02*
G37*
G36*
X341274Y-241078D02*
X340572Y-241218D01*
X339977Y-241616D01*
X339579Y-242211D01*
X339439Y-242913D01*
X339579Y-243616D01*
X339977Y-244211D01*
X340572Y-244609D01*
X341274Y-244749D01*
X341977Y-244609D01*
X342572Y-244211D01*
X342970Y-243616D01*
X343110Y-242913D01*
X342970Y-242211D01*
X342572Y-241616D01*
X341977Y-241218D01*
X341274Y-241078D01*
D02*
G37*
G36*
X309782Y-241472D02*
X309080Y-241612D01*
X308485Y-242009D01*
X308087Y-242605D01*
X307947Y-243307D01*
X308087Y-244009D01*
X308485Y-244605D01*
X309080Y-245003D01*
X309782Y-245142D01*
X310485Y-245003D01*
X311080Y-244605D01*
X311478Y-244009D01*
X311618Y-243307D01*
X311478Y-242605D01*
X311080Y-242009D01*
X310485Y-241612D01*
X309782Y-241472D01*
D02*
G37*
G36*
X550391Y-241475D02*
X549688Y-241615D01*
X549093Y-242012D01*
X548695Y-242608D01*
X548556Y-243310D01*
X548695Y-244012D01*
X549093Y-244608D01*
X549688Y-245006D01*
X550391Y-245145D01*
X551093Y-245006D01*
X551688Y-244608D01*
X552086Y-244012D01*
X552226Y-243310D01*
X552086Y-242608D01*
X551688Y-242012D01*
X551093Y-241615D01*
X550391Y-241475D01*
D02*
G37*
G36*
X524016Y-241964D02*
X523313Y-242104D01*
X522718Y-242501D01*
X522320Y-243097D01*
X522181Y-243799D01*
X522320Y-244501D01*
X522718Y-245097D01*
X523313Y-245495D01*
X524016Y-245635D01*
X524718Y-245495D01*
X525314Y-245097D01*
X525711Y-244501D01*
X525851Y-243799D01*
X525711Y-243097D01*
X525314Y-242501D01*
X524718Y-242104D01*
X524016Y-241964D01*
D02*
G37*
G36*
X496063Y-242259D02*
X495361Y-242399D01*
X494765Y-242797D01*
X494367Y-243392D01*
X494228Y-244094D01*
X494367Y-244797D01*
X494765Y-245392D01*
X495361Y-245790D01*
X496063Y-245930D01*
X496765Y-245790D01*
X497361Y-245392D01*
X497759Y-244797D01*
X497898Y-244094D01*
X497759Y-243392D01*
X497361Y-242797D01*
X496765Y-242399D01*
X496063Y-242259D01*
D02*
G37*
G36*
X418898Y-243440D02*
X418195Y-243580D01*
X417600Y-243978D01*
X417202Y-244573D01*
X417062Y-245276D01*
X417202Y-245978D01*
X417600Y-246573D01*
X418195Y-246971D01*
X418898Y-247111D01*
X419600Y-246971D01*
X420195Y-246573D01*
X420593Y-245978D01*
X420733Y-245276D01*
X420593Y-244573D01*
X420195Y-243978D01*
X419600Y-243580D01*
X418898Y-243440D01*
D02*
G37*
G36*
X319685D02*
X318983Y-243580D01*
X318387Y-243978D01*
X317989Y-244573D01*
X317850Y-245276D01*
X317989Y-245978D01*
X318387Y-246573D01*
X318983Y-246971D01*
X319685Y-247111D01*
X320387Y-246971D01*
X320983Y-246573D01*
X321381Y-245978D01*
X321520Y-245276D01*
X321381Y-244573D01*
X320983Y-243978D01*
X320387Y-243580D01*
X319685Y-243440D01*
D02*
G37*
G36*
X536614Y-243539D02*
X535912Y-243678D01*
X535316Y-244076D01*
X534919Y-244672D01*
X534779Y-245374D01*
X534919Y-246076D01*
X535316Y-246672D01*
X535912Y-247070D01*
X536614Y-247209D01*
X537317Y-247070D01*
X537912Y-246672D01*
X538310Y-246076D01*
X538449Y-245374D01*
X538310Y-244672D01*
X537912Y-244076D01*
X537317Y-243678D01*
X536614Y-243539D01*
D02*
G37*
G36*
X470472Y-244621D02*
X469770Y-244761D01*
X469175Y-245159D01*
X468777Y-245754D01*
X468637Y-246457D01*
X468777Y-247159D01*
X469175Y-247754D01*
X469770Y-248152D01*
X470472Y-248292D01*
X471175Y-248152D01*
X471770Y-247754D01*
X472168Y-247159D01*
X472308Y-246457D01*
X472168Y-245754D01*
X471770Y-245159D01*
X471175Y-244761D01*
X470472Y-244621D01*
D02*
G37*
G36*
X274719Y-243093D02*
X274016Y-243233D01*
X273421Y-243631D01*
X273023Y-244226D01*
X272884Y-244928D01*
X273023Y-245631D01*
X273421Y-246226D01*
X274016Y-246624D01*
X274719Y-246763D01*
X274955Y-246716D01*
X275060Y-247242D01*
X275457Y-247837D01*
X276053Y-248235D01*
X276755Y-248375D01*
X277457Y-248235D01*
X278053Y-247837D01*
X278451Y-247242D01*
X278590Y-246539D01*
X278451Y-245837D01*
X278053Y-245242D01*
X277457Y-244844D01*
X276755Y-244704D01*
X276519Y-244751D01*
X276414Y-244226D01*
X276016Y-243631D01*
X275421Y-243233D01*
X274719Y-243093D01*
D02*
G37*
G36*
X429134Y-245015D02*
X428432Y-245155D01*
X427836Y-245553D01*
X427438Y-246148D01*
X427299Y-246850D01*
X427438Y-247553D01*
X427836Y-248148D01*
X428432Y-248546D01*
X429134Y-248686D01*
X429836Y-248546D01*
X430432Y-248148D01*
X430829Y-247553D01*
X430969Y-246850D01*
X430829Y-246148D01*
X430432Y-245553D01*
X429836Y-245155D01*
X429134Y-245015D01*
D02*
G37*
G36*
X477165Y-245409D02*
X476463Y-245549D01*
X475868Y-245946D01*
X475470Y-246542D01*
X475330Y-247244D01*
X475470Y-247946D01*
X475868Y-248542D01*
X476463Y-248940D01*
X477165Y-249079D01*
X477868Y-248940D01*
X478463Y-248542D01*
X478861Y-247946D01*
X479001Y-247244D01*
X478861Y-246542D01*
X478463Y-245946D01*
X477868Y-245549D01*
X477165Y-245409D01*
D02*
G37*
G36*
X334842D02*
X334140Y-245549D01*
X333545Y-245946D01*
X333147Y-246542D01*
X333007Y-247244D01*
X333147Y-247946D01*
X333545Y-248542D01*
X334140Y-248940D01*
X334842Y-249079D01*
X335545Y-248940D01*
X336140Y-248542D01*
X336538Y-247946D01*
X336678Y-247244D01*
X336538Y-246542D01*
X336140Y-245946D01*
X335545Y-245549D01*
X334842Y-245409D01*
D02*
G37*
G36*
X464472Y-243705D02*
X463769Y-243844D01*
X463174Y-244242D01*
X462776Y-244838D01*
X462637Y-245540D01*
X462765Y-246185D01*
X462751Y-246188D01*
X462155Y-246586D01*
X461758Y-247181D01*
X461618Y-247883D01*
X461758Y-248586D01*
X462155Y-249181D01*
X462751Y-249579D01*
X463453Y-249719D01*
X464155Y-249579D01*
X464751Y-249181D01*
X465149Y-248586D01*
X465288Y-247883D01*
X465160Y-247238D01*
X465174Y-247236D01*
X465770Y-246838D01*
X466167Y-246242D01*
X466307Y-245540D01*
X466167Y-244838D01*
X465770Y-244242D01*
X465174Y-243844D01*
X464472Y-243705D01*
D02*
G37*
G36*
X396850Y-247181D02*
X396148Y-247320D01*
X395553Y-247718D01*
X395155Y-248313D01*
X395015Y-249016D01*
X395155Y-249718D01*
X395553Y-250313D01*
X396148Y-250711D01*
X396850Y-250851D01*
X397553Y-250711D01*
X398148Y-250313D01*
X398546Y-249718D01*
X398686Y-249016D01*
X398546Y-248313D01*
X398148Y-247718D01*
X397553Y-247320D01*
X396850Y-247181D01*
D02*
G37*
G36*
X390896Y-247230D02*
X390193Y-247369D01*
X389598Y-247767D01*
X389200Y-248363D01*
X389060Y-249065D01*
X389200Y-249767D01*
X389598Y-250363D01*
X390193Y-250761D01*
X390896Y-250900D01*
X391598Y-250761D01*
X392193Y-250363D01*
X392591Y-249767D01*
X392731Y-249065D01*
X392591Y-248363D01*
X392193Y-247767D01*
X391598Y-247369D01*
X390896Y-247230D01*
D02*
G37*
G36*
X386615Y-247278D02*
X385913Y-247418D01*
X385317Y-247815D01*
X384920Y-248411D01*
X384780Y-249113D01*
X384920Y-249816D01*
X385317Y-250411D01*
X385913Y-250809D01*
X386615Y-250949D01*
X387317Y-250809D01*
X387913Y-250411D01*
X388311Y-249816D01*
X388450Y-249113D01*
X388311Y-248411D01*
X387913Y-247815D01*
X387317Y-247418D01*
X386615Y-247278D01*
D02*
G37*
G36*
X401575Y-247377D02*
X400873Y-247517D01*
X400277Y-247915D01*
X399879Y-248510D01*
X399740Y-249213D01*
X399879Y-249915D01*
X400277Y-250510D01*
X400873Y-250908D01*
X401575Y-251048D01*
X402277Y-250908D01*
X402873Y-250510D01*
X403270Y-249915D01*
X403410Y-249213D01*
X403270Y-248510D01*
X402873Y-247915D01*
X402277Y-247517D01*
X401575Y-247377D01*
D02*
G37*
G36*
X522047Y-247869D02*
X521345Y-248009D01*
X520750Y-248407D01*
X520352Y-249002D01*
X520212Y-249705D01*
X520352Y-250407D01*
X520750Y-251002D01*
X521345Y-251400D01*
X522047Y-251540D01*
X522750Y-251400D01*
X523345Y-251002D01*
X523743Y-250407D01*
X523882Y-249705D01*
X523743Y-249002D01*
X523345Y-248407D01*
X522750Y-248009D01*
X522047Y-247869D01*
D02*
G37*
G36*
X378937Y-247968D02*
X378235Y-248108D01*
X377639Y-248505D01*
X377241Y-249101D01*
X377102Y-249803D01*
X377241Y-250505D01*
X377639Y-251101D01*
X378235Y-251499D01*
X378937Y-251638D01*
X379639Y-251499D01*
X380235Y-251101D01*
X380633Y-250505D01*
X380772Y-249803D01*
X380633Y-249101D01*
X380235Y-248505D01*
X379639Y-248108D01*
X378937Y-247968D01*
D02*
G37*
G36*
X614822Y-248323D02*
X614120Y-248463D01*
X613525Y-248860D01*
X613127Y-249456D01*
X612987Y-250158D01*
X613127Y-250860D01*
X613525Y-251456D01*
X614120Y-251854D01*
X614822Y-251993D01*
X615525Y-251854D01*
X616120Y-251456D01*
X616518Y-250860D01*
X616658Y-250158D01*
X616518Y-249456D01*
X616120Y-248860D01*
X615525Y-248463D01*
X614822Y-248323D01*
D02*
G37*
G36*
X538976Y-249051D02*
X538274Y-249190D01*
X537679Y-249588D01*
X537281Y-250184D01*
X537141Y-250886D01*
X537281Y-251588D01*
X537679Y-252184D01*
X538274Y-252581D01*
X538976Y-252721D01*
X539679Y-252581D01*
X540274Y-252184D01*
X540672Y-251588D01*
X540812Y-250886D01*
X540672Y-250184D01*
X540274Y-249588D01*
X539679Y-249190D01*
X538976Y-249051D01*
D02*
G37*
G36*
X508268Y-249838D02*
X507565Y-249978D01*
X506970Y-250376D01*
X506572Y-250971D01*
X506432Y-251673D01*
X506572Y-252376D01*
X506970Y-252971D01*
X507565Y-253369D01*
X508268Y-253508D01*
X508970Y-253369D01*
X509565Y-252971D01*
X509963Y-252376D01*
X510103Y-251673D01*
X509963Y-250971D01*
X509565Y-250376D01*
X508970Y-249978D01*
X508268Y-249838D01*
D02*
G37*
G36*
X230406Y-250026D02*
X229703Y-250166D01*
X229108Y-250564D01*
X228710Y-251159D01*
X228571Y-251861D01*
X228710Y-252564D01*
X229108Y-253159D01*
X229703Y-253557D01*
X230406Y-253697D01*
X231108Y-253557D01*
X231704Y-253159D01*
X232101Y-252564D01*
X232241Y-251861D01*
X232101Y-251159D01*
X231704Y-250564D01*
X231108Y-250166D01*
X230406Y-250026D01*
D02*
G37*
G36*
X618504Y-250527D02*
X617802Y-250667D01*
X617206Y-251064D01*
X616808Y-251660D01*
X616669Y-252362D01*
X616808Y-253064D01*
X617206Y-253660D01*
X617802Y-254058D01*
X618504Y-254198D01*
X619206Y-254058D01*
X619802Y-253660D01*
X620199Y-253064D01*
X620339Y-252362D01*
X620199Y-251660D01*
X619802Y-251064D01*
X619206Y-250667D01*
X618504Y-250527D01*
D02*
G37*
G36*
X605317Y-250921D02*
X604615Y-251060D01*
X604019Y-251458D01*
X603622Y-252054D01*
X603482Y-252756D01*
X603622Y-253458D01*
X604019Y-254054D01*
X604615Y-254451D01*
X605317Y-254591D01*
X606019Y-254451D01*
X606615Y-254054D01*
X607013Y-253458D01*
X607152Y-252756D01*
X607013Y-252054D01*
X606615Y-251458D01*
X606019Y-251060D01*
X605317Y-250921D01*
D02*
G37*
G36*
X318989Y-251189D02*
X318286Y-251329D01*
X317691Y-251727D01*
X317293Y-252322D01*
X317153Y-253024D01*
X317293Y-253727D01*
X317691Y-254322D01*
X318286Y-254720D01*
X318989Y-254860D01*
X319691Y-254720D01*
X320286Y-254322D01*
X320684Y-253727D01*
X320824Y-253024D01*
X320684Y-252322D01*
X320286Y-251727D01*
X319691Y-251329D01*
X318989Y-251189D01*
D02*
G37*
G36*
X571260Y-254956D02*
X570557Y-255096D01*
X570079Y-255416D01*
X569600Y-255096D01*
X568898Y-254956D01*
X568195Y-255096D01*
X567600Y-255494D01*
X567202Y-256089D01*
X567062Y-256791D01*
X567202Y-257494D01*
X567600Y-258089D01*
X568195Y-258487D01*
X568898Y-258627D01*
X569600Y-258487D01*
X570079Y-258167D01*
X570557Y-258487D01*
X571260Y-258627D01*
X571962Y-258487D01*
X572558Y-258089D01*
X572955Y-257494D01*
X573095Y-256791D01*
X572955Y-256089D01*
X572558Y-255494D01*
X571962Y-255096D01*
X571260Y-254956D01*
D02*
G37*
G36*
X476772Y-252200D02*
X476069Y-252340D01*
X475474Y-252738D01*
X475076Y-253333D01*
X474936Y-254035D01*
X475076Y-254738D01*
X475474Y-255333D01*
X476069Y-255731D01*
X476772Y-255871D01*
X477474Y-255731D01*
X478069Y-255333D01*
X478467Y-254738D01*
X478607Y-254035D01*
X478467Y-253333D01*
X478069Y-252738D01*
X477474Y-252340D01*
X476772Y-252200D01*
D02*
G37*
G36*
X381890Y-252495D02*
X381187Y-252635D01*
X380592Y-253033D01*
X380194Y-253628D01*
X380054Y-254331D01*
X380194Y-255033D01*
X380592Y-255628D01*
X381187Y-256026D01*
X381890Y-256166D01*
X382592Y-256026D01*
X383188Y-255628D01*
X383585Y-255033D01*
X383725Y-254331D01*
X383585Y-253628D01*
X383188Y-253033D01*
X382592Y-252635D01*
X381890Y-252495D01*
D02*
G37*
G36*
X513386Y-252594D02*
X512683Y-252734D01*
X512088Y-253131D01*
X511690Y-253727D01*
X511551Y-254429D01*
X511690Y-255131D01*
X512088Y-255727D01*
X512683Y-256125D01*
X513386Y-256264D01*
X514088Y-256125D01*
X514683Y-255727D01*
X515081Y-255131D01*
X515221Y-254429D01*
X515081Y-253727D01*
X514683Y-253131D01*
X514088Y-252734D01*
X513386Y-252594D01*
D02*
G37*
G36*
X243996Y-246819D02*
X243294Y-246959D01*
X242699Y-247357D01*
X242301Y-247952D01*
X242161Y-248655D01*
X242301Y-249357D01*
X242699Y-249952D01*
X243294Y-250350D01*
X243385Y-250368D01*
Y-250878D01*
X243294Y-250896D01*
X242699Y-251294D01*
X242301Y-251889D01*
X242161Y-252592D01*
X242301Y-253294D01*
X242699Y-253889D01*
X243294Y-254287D01*
X243725Y-254373D01*
X244130Y-254655D01*
X244269Y-255357D01*
X244667Y-255952D01*
X245263Y-256350D01*
X245965Y-256490D01*
X246667Y-256350D01*
X247263Y-255952D01*
X247660Y-255357D01*
X247800Y-254655D01*
X247660Y-253952D01*
X247263Y-253357D01*
X246667Y-252959D01*
X246418Y-252909D01*
Y-252400D01*
X246667Y-252350D01*
X247263Y-251952D01*
X247660Y-251357D01*
X247800Y-250655D01*
X247660Y-249952D01*
X247263Y-249357D01*
X246667Y-248959D01*
X246296Y-248885D01*
X245914Y-248695D01*
X245771Y-248348D01*
X245692Y-247952D01*
X245294Y-247357D01*
X244699Y-246959D01*
X243996Y-246819D01*
D02*
G37*
G36*
X432283Y-252889D02*
X431581Y-253029D01*
X430986Y-253427D01*
X430588Y-254022D01*
X430448Y-254724D01*
X430588Y-255427D01*
X430986Y-256022D01*
X431581Y-256420D01*
X432283Y-256560D01*
X432986Y-256420D01*
X433581Y-256022D01*
X433979Y-255427D01*
X434119Y-254724D01*
X433979Y-254022D01*
X433581Y-253427D01*
X432986Y-253029D01*
X432283Y-252889D01*
D02*
G37*
G36*
X203805Y-250346D02*
X203103Y-250486D01*
X202507Y-250884D01*
X202110Y-251479D01*
X201970Y-252182D01*
X202110Y-252884D01*
X202507Y-253479D01*
X202574Y-253524D01*
X202241Y-254022D01*
X202102Y-254724D01*
X202241Y-255427D01*
X202639Y-256022D01*
X203235Y-256420D01*
X203937Y-256560D01*
X204639Y-256420D01*
X205235Y-256022D01*
X205633Y-255427D01*
X205772Y-254724D01*
X205633Y-254022D01*
X205235Y-253427D01*
X205168Y-253382D01*
X205501Y-252884D01*
X205641Y-252182D01*
X205501Y-251479D01*
X205103Y-250884D01*
X204507Y-250486D01*
X203805Y-250346D01*
D02*
G37*
G36*
X462205Y-253283D02*
X461502Y-253423D01*
X460907Y-253820D01*
X460509Y-254416D01*
X460369Y-255118D01*
X460509Y-255820D01*
X460907Y-256416D01*
X461502Y-256814D01*
X462205Y-256953D01*
X462907Y-256814D01*
X463502Y-256416D01*
X463900Y-255820D01*
X464040Y-255118D01*
X463900Y-254416D01*
X463502Y-253820D01*
X462907Y-253423D01*
X462205Y-253283D01*
D02*
G37*
G36*
X518110Y-253381D02*
X517408Y-253521D01*
X516813Y-253919D01*
X516415Y-254514D01*
X516275Y-255217D01*
X516415Y-255919D01*
X516813Y-256514D01*
X517408Y-256912D01*
X518110Y-257052D01*
X518813Y-256912D01*
X519408Y-256514D01*
X519806Y-255919D01*
X519945Y-255217D01*
X519806Y-254514D01*
X519408Y-253919D01*
X518813Y-253521D01*
X518110Y-253381D01*
D02*
G37*
G36*
X550000Y-253775D02*
X549298Y-253915D01*
X548702Y-254312D01*
X548304Y-254908D01*
X548165Y-255610D01*
X548304Y-256313D01*
X548702Y-256908D01*
X549298Y-257306D01*
X550000Y-257446D01*
X550702Y-257306D01*
X551298Y-256908D01*
X551696Y-256313D01*
X551835Y-255610D01*
X551696Y-254908D01*
X551298Y-254312D01*
X550702Y-253915D01*
X550000Y-253775D01*
D02*
G37*
G36*
X540945Y-254169D02*
X540243Y-254308D01*
X539647Y-254706D01*
X539249Y-255302D01*
X539110Y-256004D01*
X539249Y-256706D01*
X539647Y-257302D01*
X540243Y-257699D01*
X540945Y-257839D01*
X541647Y-257699D01*
X542243Y-257302D01*
X542640Y-256706D01*
X542780Y-256004D01*
X542640Y-255302D01*
X542243Y-254706D01*
X541647Y-254308D01*
X540945Y-254169D01*
D02*
G37*
G36*
X487402Y-255153D02*
X486699Y-255293D01*
X486104Y-255691D01*
X485706Y-256286D01*
X485566Y-256988D01*
X485706Y-257691D01*
X486104Y-258286D01*
X486699Y-258684D01*
X487402Y-258823D01*
X488104Y-258684D01*
X488699Y-258286D01*
X489097Y-257691D01*
X489237Y-256988D01*
X489097Y-256286D01*
X488699Y-255691D01*
X488104Y-255293D01*
X487402Y-255153D01*
D02*
G37*
G36*
X500049Y-254798D02*
X499347Y-254938D01*
X498752Y-255336D01*
X498354Y-255931D01*
X498214Y-256633D01*
X498354Y-257336D01*
X498752Y-257931D01*
X499347Y-258329D01*
X500049Y-258469D01*
X500752Y-258329D01*
X500897Y-258232D01*
X501064Y-258483D01*
X501660Y-258881D01*
X502362Y-259020D01*
X503064Y-258881D01*
X503346Y-258692D01*
X503628Y-258881D01*
X504331Y-259020D01*
X505033Y-258881D01*
X505628Y-258483D01*
X506026Y-257887D01*
X506166Y-257185D01*
X506026Y-256483D01*
X505628Y-255887D01*
X505033Y-255489D01*
X504331Y-255350D01*
X503628Y-255489D01*
X503346Y-255678D01*
X503064Y-255489D01*
X502362Y-255350D01*
X501660Y-255489D01*
X501515Y-255587D01*
X501347Y-255336D01*
X500752Y-254938D01*
X500049Y-254798D01*
D02*
G37*
G36*
X473622Y-257220D02*
X472920Y-257360D01*
X472324Y-257757D01*
X471926Y-258353D01*
X471787Y-259055D01*
X471926Y-259757D01*
X472324Y-260353D01*
X472920Y-260751D01*
X473622Y-260890D01*
X474324Y-260751D01*
X474920Y-260353D01*
X475318Y-259757D01*
X475457Y-259055D01*
X475318Y-258353D01*
X474920Y-257757D01*
X474324Y-257360D01*
X473622Y-257220D01*
D02*
G37*
G36*
X337402Y-258795D02*
X336699Y-258934D01*
X336104Y-259332D01*
X335706Y-259928D01*
X335566Y-260630D01*
X335706Y-261332D01*
X336104Y-261928D01*
X336699Y-262326D01*
X337402Y-262465D01*
X338104Y-262326D01*
X338699Y-261928D01*
X339097Y-261332D01*
X339237Y-260630D01*
X339097Y-259928D01*
X338699Y-259332D01*
X338104Y-258934D01*
X337402Y-258795D01*
D02*
G37*
G36*
X596865Y-264561D02*
X596162Y-264701D01*
X595815Y-264933D01*
X595467Y-264701D01*
X594765Y-264561D01*
X594062Y-264701D01*
X593467Y-265098D01*
X593069Y-265694D01*
X592929Y-266396D01*
X593069Y-267098D01*
X593467Y-267694D01*
X594062Y-268092D01*
X594765Y-268231D01*
X595467Y-268092D01*
X595815Y-267859D01*
X596162Y-268092D01*
X596865Y-268231D01*
X597567Y-268092D01*
X598162Y-267694D01*
X598560Y-267098D01*
X598700Y-266396D01*
X598560Y-265694D01*
X598162Y-265098D01*
X597567Y-264701D01*
X596865Y-264561D01*
D02*
G37*
G36*
X244028Y-256662D02*
X243325Y-256802D01*
X242730Y-257199D01*
X242332Y-257795D01*
X242193Y-258497D01*
X242332Y-259200D01*
X242730Y-259795D01*
X243325Y-260193D01*
X243495Y-260226D01*
Y-260736D01*
X243325Y-260770D01*
X242730Y-261168D01*
X242332Y-261763D01*
X242193Y-262466D01*
X242332Y-263168D01*
X242730Y-263763D01*
X243325Y-264161D01*
X243710Y-264238D01*
X244130Y-264497D01*
X244269Y-265199D01*
X244667Y-265795D01*
X245263Y-266193D01*
X245965Y-266332D01*
X246667Y-266193D01*
X247263Y-265795D01*
X247660Y-265199D01*
X247800Y-264497D01*
X247660Y-263795D01*
X247263Y-263199D01*
X246667Y-262802D01*
X246418Y-262752D01*
Y-262242D01*
X246667Y-262193D01*
X247263Y-261795D01*
X247660Y-261199D01*
X247800Y-260497D01*
X247660Y-259795D01*
X247263Y-259199D01*
X246667Y-258802D01*
X246326Y-258734D01*
X245863Y-258497D01*
X245723Y-257795D01*
X245326Y-257199D01*
X244730Y-256802D01*
X244028Y-256662D01*
D02*
G37*
G36*
X486221Y-263913D02*
X485518Y-264053D01*
X484923Y-264450D01*
X484525Y-265046D01*
X484385Y-265748D01*
X484525Y-266450D01*
X484923Y-267046D01*
X485518Y-267444D01*
X486221Y-267583D01*
X486923Y-267444D01*
X487518Y-267046D01*
X487916Y-266450D01*
X488056Y-265748D01*
X487916Y-265046D01*
X487518Y-264450D01*
X486923Y-264053D01*
X486221Y-263913D01*
D02*
G37*
G36*
X585039Y-264306D02*
X584337Y-264446D01*
X583742Y-264844D01*
X583344Y-265439D01*
X583204Y-266142D01*
X583344Y-266844D01*
X583742Y-267439D01*
X584337Y-267837D01*
X585039Y-267977D01*
X585742Y-267837D01*
X586337Y-267439D01*
X586735Y-266844D01*
X586875Y-266142D01*
X586735Y-265439D01*
X586337Y-264844D01*
X585742Y-264446D01*
X585039Y-264306D01*
D02*
G37*
G36*
X-3528Y-258693D02*
X-13402D01*
Y-268567D01*
X-3528D01*
Y-258693D01*
D02*
G37*
G36*
X560630Y-267456D02*
X559928Y-267596D01*
X559332Y-267994D01*
X558934Y-268589D01*
X558795Y-269291D01*
X558934Y-269994D01*
X559332Y-270589D01*
X559928Y-270987D01*
X560630Y-271127D01*
X561332Y-270987D01*
X561928Y-270589D01*
X562325Y-269994D01*
X562465Y-269291D01*
X562325Y-268589D01*
X561928Y-267994D01*
X561332Y-267596D01*
X560630Y-267456D01*
D02*
G37*
G36*
X548425Y-267796D02*
X547723Y-267936D01*
X547127Y-268334D01*
X546730Y-268929D01*
X546590Y-269632D01*
X546730Y-270334D01*
X547127Y-270929D01*
X547723Y-271327D01*
X548425Y-271467D01*
X549127Y-271327D01*
X549723Y-270929D01*
X550121Y-270334D01*
X550260Y-269632D01*
X550121Y-268929D01*
X549723Y-268334D01*
X549127Y-267936D01*
X548425Y-267796D01*
D02*
G37*
G36*
X298819Y-267850D02*
X298117Y-267989D01*
X297521Y-268387D01*
X297123Y-268983D01*
X296984Y-269685D01*
X297123Y-270387D01*
X297521Y-270983D01*
X298117Y-271381D01*
X298819Y-271520D01*
X299521Y-271381D01*
X300117Y-270983D01*
X300515Y-270387D01*
X300654Y-269685D01*
X300515Y-268983D01*
X300117Y-268387D01*
X299521Y-267989D01*
X298819Y-267850D01*
D02*
G37*
G36*
X522047Y-269031D02*
X521345Y-269171D01*
X520750Y-269568D01*
X520352Y-270164D01*
X520212Y-270866D01*
X520352Y-271568D01*
X520750Y-272164D01*
X521345Y-272562D01*
X522047Y-272701D01*
X522750Y-272562D01*
X523345Y-272164D01*
X523743Y-271568D01*
X523882Y-270866D01*
X523743Y-270164D01*
X523345Y-269568D01*
X522750Y-269171D01*
X522047Y-269031D01*
D02*
G37*
G36*
X575197Y-268166D02*
X574370Y-268274D01*
X573600Y-268593D01*
X572939Y-269101D01*
X572432Y-269762D01*
X572113Y-270532D01*
X572004Y-271358D01*
X572113Y-272185D01*
X572432Y-272955D01*
X572939Y-273616D01*
X573600Y-274123D01*
X574370Y-274442D01*
X575197Y-274551D01*
X576023Y-274442D01*
X576793Y-274123D01*
X577454Y-273616D01*
X577962Y-272955D01*
X578281Y-272185D01*
X578390Y-271358D01*
X578281Y-270532D01*
X577962Y-269762D01*
X577454Y-269101D01*
X576793Y-268593D01*
X576023Y-268274D01*
X575197Y-268166D01*
D02*
G37*
G36*
X476378Y-271787D02*
X475676Y-271926D01*
X475080Y-272324D01*
X474682Y-272920D01*
X474543Y-273622D01*
X474682Y-274324D01*
X475080Y-274920D01*
X475676Y-275318D01*
X476378Y-275457D01*
X477080Y-275318D01*
X477676Y-274920D01*
X478074Y-274324D01*
X478213Y-273622D01*
X478074Y-272920D01*
X477676Y-272324D01*
X477080Y-271926D01*
X476378Y-271787D01*
D02*
G37*
G36*
X496457Y-267173D02*
X495373Y-267316D01*
X494364Y-267734D01*
X493497Y-268399D01*
X492832Y-269266D01*
X492414Y-270275D01*
X492271Y-271358D01*
X492414Y-272442D01*
X492832Y-273451D01*
X493497Y-274318D01*
X494364Y-274983D01*
X495373Y-275401D01*
X496457Y-275544D01*
X497540Y-275401D01*
X498549Y-274983D01*
X499416Y-274318D01*
X500081Y-273451D01*
X500499Y-272442D01*
X500642Y-271358D01*
X500499Y-270275D01*
X500081Y-269266D01*
X499416Y-268399D01*
X498549Y-267734D01*
X497540Y-267316D01*
X496457Y-267173D01*
D02*
G37*
G36*
X280382Y-272441D02*
X279679Y-272581D01*
X279084Y-272979D01*
X278686Y-273574D01*
X278547Y-274277D01*
X278686Y-274979D01*
X279084Y-275574D01*
X279679Y-275972D01*
X280382Y-276112D01*
X281084Y-275972D01*
X281680Y-275574D01*
X282077Y-274979D01*
X282217Y-274277D01*
X282077Y-273574D01*
X281680Y-272979D01*
X281084Y-272581D01*
X280382Y-272441D01*
D02*
G37*
G36*
X473303Y-274641D02*
X472601Y-274781D01*
X472006Y-275179D01*
X471608Y-275774D01*
X471468Y-276476D01*
X471608Y-277179D01*
X472006Y-277774D01*
X472601Y-278172D01*
X473303Y-278312D01*
X474006Y-278172D01*
X474601Y-277774D01*
X474999Y-277179D01*
X475139Y-276476D01*
X474999Y-275774D01*
X474601Y-275179D01*
X474006Y-274781D01*
X473303Y-274641D01*
D02*
G37*
G36*
X383071Y-274936D02*
X382369Y-275076D01*
X381773Y-275474D01*
X381375Y-276069D01*
X381236Y-276772D01*
X381375Y-277474D01*
X381773Y-278069D01*
X382369Y-278467D01*
X383071Y-278607D01*
X383773Y-278467D01*
X384369Y-278069D01*
X384766Y-277474D01*
X384906Y-276772D01*
X384766Y-276069D01*
X384369Y-275474D01*
X383773Y-275076D01*
X383071Y-274936D01*
D02*
G37*
G36*
X462473Y-275800D02*
X461771Y-275940D01*
X461175Y-276338D01*
X460778Y-276933D01*
X460638Y-277635D01*
X460778Y-278338D01*
X461175Y-278933D01*
X461771Y-279331D01*
X462473Y-279470D01*
X463176Y-279331D01*
X463771Y-278933D01*
X464169Y-278338D01*
X464309Y-277635D01*
X464169Y-276933D01*
X463771Y-276338D01*
X463176Y-275940D01*
X462473Y-275800D01*
D02*
G37*
G36*
X391339Y-276117D02*
X390636Y-276257D01*
X390041Y-276655D01*
X389643Y-277250D01*
X389503Y-277953D01*
X389643Y-278655D01*
X390041Y-279251D01*
X390636Y-279648D01*
X391339Y-279788D01*
X392041Y-279648D01*
X392636Y-279251D01*
X393034Y-278655D01*
X393174Y-277953D01*
X393034Y-277250D01*
X392636Y-276655D01*
X392041Y-276257D01*
X391339Y-276117D01*
D02*
G37*
G36*
X341339D02*
X340636Y-276257D01*
X340041Y-276655D01*
X339643Y-277250D01*
X339503Y-277953D01*
X339643Y-278655D01*
X340041Y-279251D01*
X340636Y-279648D01*
X341339Y-279788D01*
X342041Y-279648D01*
X342636Y-279251D01*
X343034Y-278655D01*
X343174Y-277953D01*
X343034Y-277250D01*
X342636Y-276655D01*
X342041Y-276257D01*
X341339Y-276117D01*
D02*
G37*
G36*
X240158Y-276905D02*
X239455Y-277045D01*
X238860Y-277442D01*
X238462Y-278038D01*
X238322Y-278740D01*
X238462Y-279443D01*
X238860Y-280038D01*
X239455Y-280436D01*
X240158Y-280575D01*
X240860Y-280436D01*
X241455Y-280038D01*
X241853Y-279443D01*
X241993Y-278740D01*
X241853Y-278038D01*
X241455Y-277442D01*
X240860Y-277045D01*
X240158Y-276905D01*
D02*
G37*
G36*
X485827Y-277594D02*
X485124Y-277734D01*
X484529Y-278131D01*
X484131Y-278727D01*
X483991Y-279429D01*
X484131Y-280132D01*
X484529Y-280727D01*
X485124Y-281125D01*
X485827Y-281264D01*
X486529Y-281125D01*
X487124Y-280727D01*
X487522Y-280132D01*
X487662Y-279429D01*
X487522Y-278727D01*
X487124Y-278131D01*
X486529Y-277734D01*
X485827Y-277594D01*
D02*
G37*
G36*
X364173Y-278480D02*
X363471Y-278619D01*
X362876Y-279017D01*
X362478Y-279613D01*
X362338Y-280315D01*
X362478Y-281017D01*
X362876Y-281613D01*
X363471Y-282011D01*
X364173Y-282150D01*
X364876Y-282011D01*
X365471Y-281613D01*
X365869Y-281017D01*
X366008Y-280315D01*
X365869Y-279613D01*
X365471Y-279017D01*
X364876Y-278619D01*
X364173Y-278480D01*
D02*
G37*
G36*
X574406Y-278972D02*
X573703Y-279111D01*
X573108Y-279509D01*
X572710Y-280104D01*
X572571Y-280807D01*
X572710Y-281509D01*
X573108Y-282104D01*
X573703Y-282502D01*
X574406Y-282642D01*
X575108Y-282502D01*
X575703Y-282104D01*
X576101Y-281509D01*
X576241Y-280807D01*
X576101Y-280104D01*
X575703Y-279509D01*
X575108Y-279111D01*
X574406Y-278972D01*
D02*
G37*
G36*
X402756Y-279267D02*
X402054Y-279407D01*
X401458Y-279805D01*
X401060Y-280400D01*
X400921Y-281102D01*
X401060Y-281805D01*
X401458Y-282400D01*
X402054Y-282798D01*
X402756Y-282938D01*
X403458Y-282798D01*
X404054Y-282400D01*
X404452Y-281805D01*
X404591Y-281102D01*
X404452Y-280400D01*
X404054Y-279805D01*
X403458Y-279407D01*
X402756Y-279267D01*
D02*
G37*
G36*
X-4724Y-281236D02*
X-5427Y-281375D01*
X-6022Y-281773D01*
X-6420Y-282368D01*
X-6560Y-283071D01*
X-6420Y-283773D01*
X-6022Y-284369D01*
X-5427Y-284766D01*
X-4724Y-284906D01*
X-4022Y-284766D01*
X-3427Y-284369D01*
X-3029Y-283773D01*
X-2889Y-283071D01*
X-3029Y-282368D01*
X-3427Y-281773D01*
X-4022Y-281375D01*
X-4724Y-281236D01*
D02*
G37*
G36*
X321850Y-281629D02*
X321148Y-281769D01*
X320553Y-282167D01*
X320155Y-282762D01*
X320015Y-283465D01*
X320155Y-284167D01*
X320553Y-284762D01*
X321148Y-285160D01*
X321850Y-285300D01*
X322553Y-285160D01*
X323148Y-284762D01*
X323546Y-284167D01*
X323686Y-283465D01*
X323546Y-282762D01*
X323148Y-282167D01*
X322553Y-281769D01*
X321850Y-281629D01*
D02*
G37*
G36*
X313386D02*
X312684Y-281769D01*
X312088Y-282167D01*
X311690Y-282762D01*
X311551Y-283465D01*
X311690Y-284167D01*
X312088Y-284762D01*
X312684Y-285160D01*
X313386Y-285300D01*
X314088Y-285160D01*
X314684Y-284762D01*
X315081Y-284167D01*
X315221Y-283465D01*
X315081Y-282762D01*
X314684Y-282167D01*
X314088Y-281769D01*
X313386Y-281629D01*
D02*
G37*
G36*
X336614Y-284385D02*
X335912Y-284525D01*
X335316Y-284923D01*
X334919Y-285518D01*
X334779Y-286221D01*
X334919Y-286923D01*
X335316Y-287518D01*
X335912Y-287916D01*
X336614Y-288056D01*
X337316Y-287916D01*
X337912Y-287518D01*
X338310Y-286923D01*
X338449Y-286221D01*
X338310Y-285518D01*
X337912Y-284923D01*
X337316Y-284525D01*
X336614Y-284385D01*
D02*
G37*
G36*
X280414Y-281643D02*
X279711Y-281783D01*
X279116Y-282181D01*
X278718Y-282776D01*
X278578Y-283478D01*
X278718Y-284180D01*
X279116Y-284776D01*
X279711Y-285174D01*
X279960Y-285223D01*
Y-285733D01*
X279711Y-285783D01*
X279116Y-286180D01*
X278718Y-286776D01*
X278578Y-287478D01*
X278718Y-288180D01*
X279116Y-288776D01*
X279711Y-289174D01*
X280414Y-289314D01*
X281116Y-289174D01*
X281711Y-288776D01*
X282109Y-288180D01*
X282249Y-287478D01*
X282109Y-286776D01*
X281711Y-286180D01*
X281116Y-285783D01*
X280867Y-285733D01*
Y-285223D01*
X281116Y-285174D01*
X281711Y-284776D01*
X282109Y-284180D01*
X282249Y-283478D01*
X282109Y-282776D01*
X281711Y-282181D01*
X281116Y-281783D01*
X280414Y-281643D01*
D02*
G37*
G36*
X315945Y-285960D02*
X315243Y-286100D01*
X314647Y-286498D01*
X314249Y-287093D01*
X314110Y-287795D01*
X314249Y-288498D01*
X314647Y-289093D01*
X315243Y-289491D01*
X315945Y-289631D01*
X316647Y-289491D01*
X317243Y-289093D01*
X317640Y-288498D01*
X317780Y-287795D01*
X317640Y-287093D01*
X317243Y-286498D01*
X316647Y-286100D01*
X315945Y-285960D01*
D02*
G37*
G36*
X35039Y-283992D02*
X34337Y-284131D01*
X33742Y-284529D01*
X33344Y-285124D01*
X33204Y-285827D01*
X33344Y-286529D01*
X33742Y-287124D01*
X34337Y-287522D01*
X34923Y-287639D01*
Y-288149D01*
X34676Y-288198D01*
X34337Y-288265D01*
X33742Y-288663D01*
X33344Y-289258D01*
X33204Y-289961D01*
X33344Y-290663D01*
X33742Y-291258D01*
X34337Y-291656D01*
X35039Y-291796D01*
X35742Y-291656D01*
X36337Y-291258D01*
X36735Y-290663D01*
X36875Y-289961D01*
X36735Y-289258D01*
X36337Y-288663D01*
X35742Y-288265D01*
X35156Y-288149D01*
Y-287639D01*
X35402Y-287590D01*
X35742Y-287522D01*
X36337Y-287124D01*
X36735Y-286529D01*
X36875Y-285827D01*
X36735Y-285124D01*
X36337Y-284529D01*
X35742Y-284131D01*
X35039Y-283992D01*
D02*
G37*
G36*
X483465Y-289700D02*
X482762Y-289840D01*
X482167Y-290238D01*
X481769Y-290833D01*
X481629Y-291535D01*
X481769Y-292238D01*
X482167Y-292833D01*
X482762Y-293231D01*
X483465Y-293371D01*
X484167Y-293231D01*
X484762Y-292833D01*
X485160Y-292238D01*
X485300Y-291535D01*
X485160Y-290833D01*
X484762Y-290238D01*
X484167Y-289840D01*
X483465Y-289700D01*
D02*
G37*
G36*
X284646Y-289897D02*
X283943Y-290037D01*
X283348Y-290435D01*
X282950Y-291030D01*
X282810Y-291732D01*
X282950Y-292435D01*
X283348Y-293030D01*
X283943Y-293428D01*
X284646Y-293567D01*
X285348Y-293428D01*
X285943Y-293030D01*
X286341Y-292435D01*
X286481Y-291732D01*
X286341Y-291030D01*
X285943Y-290435D01*
X285348Y-290037D01*
X284646Y-289897D01*
D02*
G37*
G36*
X432579Y-281415D02*
X431877Y-281555D01*
X431281Y-281953D01*
X430884Y-282548D01*
X430744Y-283251D01*
X430884Y-283953D01*
X431281Y-284548D01*
X431322Y-284576D01*
Y-285075D01*
X431281Y-285103D01*
X430884Y-285698D01*
X430744Y-286400D01*
X430884Y-287103D01*
X431214Y-287598D01*
X431423Y-288060D01*
X431025Y-288655D01*
X430885Y-289358D01*
X431025Y-290060D01*
X431414Y-290642D01*
X431139Y-291053D01*
X431000Y-291755D01*
X431139Y-292457D01*
X431537Y-293053D01*
X432132Y-293450D01*
X432835Y-293590D01*
X433537Y-293450D01*
X434132Y-293053D01*
X434530Y-292457D01*
X434670Y-291755D01*
X434530Y-291053D01*
X434141Y-290471D01*
X434416Y-290060D01*
X434556Y-289358D01*
X434416Y-288655D01*
X434085Y-288160D01*
X433877Y-287698D01*
X434275Y-287103D01*
X434414Y-286400D01*
X434275Y-285698D01*
X433877Y-285103D01*
X433836Y-285075D01*
Y-284576D01*
X433877Y-284548D01*
X434275Y-283953D01*
X434414Y-283251D01*
X434275Y-282548D01*
X433877Y-281953D01*
X433281Y-281555D01*
X432579Y-281415D01*
D02*
G37*
G36*
X10630Y-290291D02*
X9928Y-290430D01*
X9332Y-290828D01*
X8934Y-291424D01*
X8795Y-292126D01*
X8934Y-292828D01*
X9332Y-293424D01*
X9928Y-293822D01*
X10630Y-293961D01*
X11332Y-293822D01*
X11928Y-293424D01*
X12325Y-292828D01*
X12465Y-292126D01*
X12325Y-291424D01*
X11928Y-290828D01*
X11332Y-290430D01*
X10630Y-290291D01*
D02*
G37*
G36*
X345161Y-291078D02*
X344459Y-291218D01*
X343863Y-291616D01*
X343465Y-292211D01*
X343326Y-292913D01*
X343465Y-293616D01*
X343863Y-294211D01*
X344459Y-294609D01*
X345161Y-294749D01*
X345863Y-294609D01*
X346459Y-294211D01*
X346856Y-293616D01*
X346996Y-292913D01*
X346856Y-292211D01*
X346459Y-291616D01*
X345863Y-291218D01*
X345161Y-291078D01*
D02*
G37*
G36*
X325776Y-291865D02*
X325074Y-292005D01*
X324478Y-292403D01*
X324080Y-292999D01*
X323941Y-293701D01*
X324080Y-294403D01*
X324478Y-294999D01*
X325074Y-295396D01*
X325776Y-295536D01*
X326478Y-295396D01*
X327074Y-294999D01*
X327472Y-294403D01*
X327611Y-293701D01*
X327472Y-292999D01*
X327074Y-292403D01*
X326478Y-292005D01*
X325776Y-291865D01*
D02*
G37*
G36*
X246162Y-291898D02*
X245459Y-292038D01*
X244864Y-292436D01*
X244466Y-293031D01*
X244326Y-293733D01*
X244466Y-294436D01*
X244864Y-295031D01*
X245459Y-295429D01*
X246162Y-295569D01*
X246864Y-295429D01*
X247459Y-295031D01*
X247857Y-294436D01*
X247997Y-293733D01*
X247857Y-293031D01*
X247459Y-292436D01*
X246864Y-292038D01*
X246162Y-291898D01*
D02*
G37*
G36*
X280414Y-291947D02*
X279711Y-292087D01*
X279116Y-292484D01*
X278718Y-293080D01*
X278578Y-293782D01*
X278718Y-294484D01*
X279116Y-295080D01*
X279711Y-295478D01*
X280414Y-295617D01*
X281116Y-295478D01*
X281711Y-295080D01*
X282109Y-294484D01*
X282249Y-293782D01*
X282109Y-293080D01*
X281711Y-292484D01*
X281116Y-292087D01*
X280414Y-291947D01*
D02*
G37*
G36*
X-23622Y-280645D02*
X-24324Y-280785D01*
X-24920Y-281183D01*
X-25318Y-281778D01*
X-25457Y-282480D01*
X-25318Y-283183D01*
X-24920Y-283778D01*
X-24324Y-284176D01*
X-24234Y-284194D01*
Y-284704D01*
X-24324Y-284722D01*
X-24920Y-285120D01*
X-25318Y-285715D01*
X-25457Y-286417D01*
X-25318Y-287120D01*
X-24920Y-287715D01*
X-24324Y-288113D01*
X-24234Y-288131D01*
Y-288641D01*
X-24324Y-288659D01*
X-24920Y-289057D01*
X-25318Y-289652D01*
X-25457Y-290354D01*
X-25318Y-291057D01*
X-24920Y-291652D01*
X-24324Y-292050D01*
X-24234Y-292068D01*
Y-292578D01*
X-24324Y-292596D01*
X-24920Y-292994D01*
X-25318Y-293589D01*
X-25457Y-294291D01*
X-25318Y-294994D01*
X-24920Y-295589D01*
X-24324Y-295987D01*
X-23622Y-296127D01*
X-22920Y-295987D01*
X-22324Y-295589D01*
X-21926Y-294994D01*
X-21787Y-294291D01*
X-21926Y-293589D01*
X-22324Y-292994D01*
X-22920Y-292596D01*
X-23010Y-292578D01*
Y-292068D01*
X-22920Y-292050D01*
X-22324Y-291652D01*
X-21926Y-291057D01*
X-21787Y-290354D01*
X-21926Y-289652D01*
X-22324Y-289057D01*
X-22920Y-288659D01*
X-23010Y-288641D01*
Y-288131D01*
X-22920Y-288113D01*
X-22324Y-287715D01*
X-21926Y-287120D01*
X-21787Y-286417D01*
X-21926Y-285715D01*
X-22324Y-285120D01*
X-22920Y-284722D01*
X-23010Y-284704D01*
Y-284194D01*
X-22920Y-284176D01*
X-22324Y-283778D01*
X-21926Y-283183D01*
X-21787Y-282480D01*
X-21926Y-281778D01*
X-22324Y-281183D01*
X-22920Y-280785D01*
X-23622Y-280645D01*
D02*
G37*
G36*
X14173Y-292484D02*
X13471Y-292624D01*
X12876Y-293022D01*
X12478Y-293617D01*
X12338Y-294320D01*
X12478Y-295022D01*
X12876Y-295617D01*
X13471Y-296015D01*
X14173Y-296155D01*
X14876Y-296015D01*
X15471Y-295617D01*
X15869Y-295022D01*
X16008Y-294320D01*
X15869Y-293617D01*
X15471Y-293022D01*
X14876Y-292624D01*
X14173Y-292484D01*
D02*
G37*
G36*
X476772Y-290094D02*
X476069Y-290234D01*
X475474Y-290631D01*
X475076Y-291227D01*
X474936Y-291929D01*
X475076Y-292631D01*
X475474Y-293227D01*
X476069Y-293625D01*
X476772Y-293764D01*
X477213Y-293676D01*
X477295Y-293725D01*
X477601Y-294095D01*
X477495Y-294626D01*
X477635Y-295329D01*
X478033Y-295924D01*
X478628Y-296322D01*
X479331Y-296462D01*
X480033Y-296322D01*
X480628Y-295924D01*
X481026Y-295329D01*
X481166Y-294626D01*
X481026Y-293924D01*
X480628Y-293329D01*
X480033Y-292931D01*
X479331Y-292791D01*
X478889Y-292879D01*
X478807Y-292831D01*
X478501Y-292460D01*
X478607Y-291929D01*
X478467Y-291227D01*
X478069Y-290631D01*
X477474Y-290234D01*
X476772Y-290094D01*
D02*
G37*
G36*
X261082Y-292579D02*
X260269Y-292740D01*
X259580Y-293201D01*
X259120Y-293890D01*
X258958Y-294702D01*
X259120Y-295515D01*
X259580Y-296204D01*
X260269Y-296665D01*
X261082Y-296826D01*
X261894Y-296665D01*
X262584Y-296204D01*
X263044Y-295515D01*
X263206Y-294702D01*
X263044Y-293890D01*
X262584Y-293201D01*
X261894Y-292740D01*
X261082Y-292579D01*
D02*
G37*
G36*
X448573Y-292588D02*
X447760Y-292750D01*
X447071Y-293210D01*
X446611Y-293899D01*
X446449Y-294712D01*
X446611Y-295525D01*
X447071Y-296214D01*
X447760Y-296674D01*
X448573Y-296836D01*
X449385Y-296674D01*
X450074Y-296214D01*
X450535Y-295525D01*
X450697Y-294712D01*
X450535Y-293899D01*
X450074Y-293210D01*
X449385Y-292750D01*
X448573Y-292588D01*
D02*
G37*
G36*
X551968Y-295802D02*
X551266Y-295942D01*
X550671Y-296340D01*
X550273Y-296936D01*
X550133Y-297638D01*
X550273Y-298340D01*
X550671Y-298936D01*
X551266Y-299333D01*
X551968Y-299473D01*
X552671Y-299333D01*
X553266Y-298936D01*
X553664Y-298340D01*
X553804Y-297638D01*
X553664Y-296936D01*
X553266Y-296340D01*
X552671Y-295942D01*
X551968Y-295802D01*
D02*
G37*
G36*
X507480Y-296295D02*
X506778Y-296434D01*
X506183Y-296832D01*
X505785Y-297428D01*
X505645Y-298130D01*
X505785Y-298832D01*
X506183Y-299428D01*
X506778Y-299826D01*
X507480Y-299965D01*
X508183Y-299826D01*
X508778Y-299428D01*
X509176Y-298832D01*
X509316Y-298130D01*
X509176Y-297428D01*
X508778Y-296832D01*
X508183Y-296434D01*
X507480Y-296295D01*
D02*
G37*
G36*
X466142Y-292850D02*
X465439Y-292989D01*
X464844Y-293387D01*
X464446Y-293983D01*
X464306Y-294685D01*
X464446Y-295387D01*
X464844Y-295983D01*
X465103Y-296156D01*
Y-296757D01*
X464844Y-296931D01*
X464446Y-297526D01*
X464306Y-298228D01*
X464446Y-298931D01*
X464844Y-299526D01*
X465439Y-299924D01*
X466142Y-300064D01*
X466844Y-299924D01*
X467440Y-299526D01*
X467837Y-298931D01*
X467977Y-298228D01*
X467837Y-297526D01*
X467440Y-296931D01*
X467180Y-296757D01*
Y-296156D01*
X467440Y-295983D01*
X467837Y-295387D01*
X467977Y-294685D01*
X467837Y-293983D01*
X467440Y-293387D01*
X466844Y-292989D01*
X466142Y-292850D01*
D02*
G37*
G36*
X27067Y-296891D02*
X26365Y-297031D01*
X25769Y-297429D01*
X25371Y-298024D01*
X25232Y-298727D01*
X25371Y-299429D01*
X25769Y-300024D01*
X26365Y-300422D01*
X27067Y-300562D01*
X27769Y-300422D01*
X28365Y-300024D01*
X28763Y-299429D01*
X28902Y-298727D01*
X28763Y-298024D01*
X28365Y-297429D01*
X27769Y-297031D01*
X27067Y-296891D01*
D02*
G37*
G36*
X336811Y-297563D02*
X336109Y-297703D01*
X335513Y-298101D01*
X335116Y-298696D01*
X334976Y-299399D01*
X335116Y-300101D01*
X335513Y-300696D01*
X336109Y-301094D01*
X336811Y-301234D01*
X337513Y-301094D01*
X338109Y-300696D01*
X338507Y-300101D01*
X338646Y-299399D01*
X338507Y-298696D01*
X338109Y-298101D01*
X337513Y-297703D01*
X336811Y-297563D01*
D02*
G37*
G36*
X315333Y-297595D02*
X314631Y-297735D01*
X314036Y-298133D01*
X313638Y-298728D01*
X313498Y-299430D01*
X313638Y-300133D01*
X314036Y-300728D01*
X314631Y-301126D01*
X315333Y-301266D01*
X316036Y-301126D01*
X316631Y-300728D01*
X317029Y-300133D01*
X317169Y-299430D01*
X317029Y-298728D01*
X316631Y-298133D01*
X316036Y-297735D01*
X315333Y-297595D01*
D02*
G37*
G36*
X610236Y-298165D02*
X609534Y-298304D01*
X608939Y-298702D01*
X608541Y-299298D01*
X608401Y-300000D01*
X608541Y-300702D01*
X608939Y-301298D01*
X609534Y-301696D01*
X610236Y-301835D01*
X610939Y-301696D01*
X611534Y-301298D01*
X611932Y-300702D01*
X612072Y-300000D01*
X611932Y-299298D01*
X611534Y-298702D01*
X610939Y-298304D01*
X610236Y-298165D01*
D02*
G37*
G36*
X308268D02*
X307565Y-298304D01*
X306970Y-298702D01*
X306572Y-299298D01*
X306433Y-300000D01*
X306572Y-300702D01*
X306970Y-301298D01*
X307565Y-301696D01*
X308268Y-301835D01*
X308970Y-301696D01*
X309565Y-301298D01*
X309963Y-300702D01*
X310103Y-300000D01*
X309963Y-299298D01*
X309565Y-298702D01*
X308970Y-298304D01*
X308268Y-298165D01*
D02*
G37*
G36*
X495866Y-301708D02*
X495164Y-301848D01*
X494568Y-302246D01*
X494395Y-302505D01*
X493794D01*
X493621Y-302246D01*
X493025Y-301848D01*
X492323Y-301708D01*
X491620Y-301848D01*
X491025Y-302246D01*
X490627Y-302841D01*
X490488Y-303543D01*
X490627Y-304246D01*
X491025Y-304841D01*
X491620Y-305239D01*
X492323Y-305379D01*
X493025Y-305239D01*
X493621Y-304841D01*
X493794Y-304582D01*
X494395D01*
X494568Y-304841D01*
X495164Y-305239D01*
X495866Y-305379D01*
X496568Y-305239D01*
X497164Y-304841D01*
X497562Y-304246D01*
X497701Y-303543D01*
X497562Y-302841D01*
X497164Y-302246D01*
X496568Y-301848D01*
X495866Y-301708D01*
D02*
G37*
G36*
X548819Y-298952D02*
X548117Y-299092D01*
X547521Y-299490D01*
X547123Y-300085D01*
X546984Y-300787D01*
X547123Y-301490D01*
X547521Y-302085D01*
X548117Y-302483D01*
X548819Y-302623D01*
X549521Y-302483D01*
X550117Y-302085D01*
X550515Y-301490D01*
X550654Y-300787D01*
X550515Y-300085D01*
X550117Y-299490D01*
X549521Y-299092D01*
X548819Y-298952D01*
D02*
G37*
G36*
X530709D02*
X530006Y-299092D01*
X529411Y-299490D01*
X529013Y-300085D01*
X528873Y-300787D01*
X529013Y-301490D01*
X529411Y-302085D01*
X530006Y-302483D01*
X530709Y-302623D01*
X531411Y-302483D01*
X532006Y-302085D01*
X532404Y-301490D01*
X532544Y-300787D01*
X532404Y-300085D01*
X532006Y-299490D01*
X531411Y-299092D01*
X530709Y-298952D01*
D02*
G37*
G36*
X324184Y-300358D02*
X323482Y-300498D01*
X322887Y-300896D01*
X322489Y-301491D01*
X322349Y-302194D01*
X322489Y-302896D01*
X322887Y-303491D01*
X323482Y-303889D01*
X324184Y-304029D01*
X324887Y-303889D01*
X325482Y-303491D01*
X325880Y-302896D01*
X326020Y-302194D01*
X325880Y-301491D01*
X325482Y-300896D01*
X324887Y-300498D01*
X324184Y-300358D01*
D02*
G37*
G36*
X513406Y-301067D02*
X512704Y-301207D01*
X512108Y-301605D01*
X511710Y-302200D01*
X511571Y-302902D01*
X511710Y-303605D01*
X512108Y-304200D01*
X512704Y-304598D01*
X513406Y-304738D01*
X514108Y-304598D01*
X514704Y-304200D01*
X515101Y-303605D01*
X515241Y-302902D01*
X515101Y-302200D01*
X514704Y-301605D01*
X514108Y-301207D01*
X513406Y-301067D01*
D02*
G37*
G36*
X569685Y-301314D02*
X568983Y-301454D01*
X568387Y-301852D01*
X567989Y-302447D01*
X567850Y-303150D01*
X567989Y-303852D01*
X568387Y-304447D01*
X568983Y-304845D01*
X569685Y-304985D01*
X570387Y-304845D01*
X570983Y-304447D01*
X571381Y-303852D01*
X571520Y-303150D01*
X571381Y-302447D01*
X570983Y-301852D01*
X570387Y-301454D01*
X569685Y-301314D01*
D02*
G37*
G36*
X552756Y-303283D02*
X552054Y-303423D01*
X551458Y-303820D01*
X551060Y-304416D01*
X550921Y-305118D01*
X551060Y-305820D01*
X551458Y-306416D01*
X552054Y-306814D01*
X552756Y-306953D01*
X553458Y-306814D01*
X554054Y-306416D01*
X554452Y-305820D01*
X554591Y-305118D01*
X554452Y-304416D01*
X554054Y-303820D01*
X553458Y-303423D01*
X552756Y-303283D01*
D02*
G37*
G36*
X544882D02*
X544180Y-303423D01*
X543584Y-303820D01*
X543186Y-304416D01*
X543047Y-305118D01*
X543186Y-305820D01*
X543584Y-306416D01*
X544180Y-306814D01*
X544882Y-306953D01*
X545584Y-306814D01*
X546180Y-306416D01*
X546578Y-305820D01*
X546717Y-305118D01*
X546578Y-304416D01*
X546180Y-303820D01*
X545584Y-303423D01*
X544882Y-303283D01*
D02*
G37*
G36*
X461024Y-300921D02*
X460321Y-301060D01*
X459726Y-301458D01*
X459328Y-302054D01*
X459188Y-302756D01*
X459328Y-303458D01*
X459726Y-304054D01*
X459890Y-304164D01*
X459722Y-304416D01*
X459582Y-305118D01*
X459722Y-305820D01*
X460120Y-306416D01*
X460715Y-306814D01*
X461417Y-306953D01*
X462120Y-306814D01*
X462715Y-306416D01*
X463113Y-305820D01*
X463253Y-305118D01*
X463113Y-304416D01*
X462715Y-303820D01*
X462551Y-303711D01*
X462719Y-303458D01*
X462859Y-302756D01*
X462719Y-302054D01*
X462321Y-301458D01*
X461726Y-301060D01*
X461024Y-300921D01*
D02*
G37*
G36*
X498425Y-305251D02*
X497723Y-305391D01*
X497127Y-305789D01*
X496730Y-306384D01*
X496590Y-307087D01*
X496730Y-307789D01*
X497022Y-308227D01*
X496740Y-308681D01*
X496620Y-308657D01*
X495918Y-308797D01*
X495322Y-309194D01*
X495235Y-309325D01*
X494650Y-309300D01*
X494408Y-308939D01*
X493813Y-308541D01*
X493110Y-308401D01*
X492408Y-308541D01*
X491813Y-308939D01*
X491639Y-309198D01*
X491038D01*
X490865Y-308939D01*
X490269Y-308541D01*
X489567Y-308401D01*
X488865Y-308541D01*
X488269Y-308939D01*
X487871Y-309534D01*
X487732Y-310236D01*
X487871Y-310939D01*
X488269Y-311534D01*
X488865Y-311932D01*
X489567Y-312071D01*
X490269Y-311932D01*
X490865Y-311534D01*
X491038Y-311275D01*
X491639D01*
X491813Y-311534D01*
X492408Y-311932D01*
X493110Y-312071D01*
X493813Y-311932D01*
X494408Y-311534D01*
X494495Y-311404D01*
X495080Y-311428D01*
X495322Y-311790D01*
X495918Y-312188D01*
X496620Y-312327D01*
X497322Y-312188D01*
X497918Y-311790D01*
X498315Y-311194D01*
X498455Y-310492D01*
X498315Y-309790D01*
X498023Y-309352D01*
X498306Y-308898D01*
X498425Y-308922D01*
X499127Y-308782D01*
X499723Y-308384D01*
X500121Y-307789D01*
X500260Y-307087D01*
X500121Y-306384D01*
X499723Y-305789D01*
X499127Y-305391D01*
X498425Y-305251D01*
D02*
G37*
G36*
X454775Y-306730D02*
X454073Y-306870D01*
X453478Y-307268D01*
X453080Y-307863D01*
X452940Y-308565D01*
X453080Y-309268D01*
X453478Y-309863D01*
X454073Y-310261D01*
X454775Y-310401D01*
X455478Y-310261D01*
X456073Y-309863D01*
X456471Y-309268D01*
X456611Y-308565D01*
X456471Y-307863D01*
X456073Y-307268D01*
X455478Y-306870D01*
X454775Y-306730D01*
D02*
G37*
G36*
X461417Y-310263D02*
X460715Y-310403D01*
X460120Y-310801D01*
X459722Y-311396D01*
X459582Y-312099D01*
X459722Y-312801D01*
X460120Y-313396D01*
X460715Y-313794D01*
X461417Y-313934D01*
X462120Y-313794D01*
X462715Y-313396D01*
X463113Y-312801D01*
X463253Y-312099D01*
X463113Y-311396D01*
X462715Y-310801D01*
X462120Y-310403D01*
X461417Y-310263D01*
D02*
G37*
G36*
X622221Y-311646D02*
X621519Y-311785D01*
X620923Y-312183D01*
X620525Y-312778D01*
X620386Y-313481D01*
X620525Y-314183D01*
X620923Y-314778D01*
X621519Y-315176D01*
X622221Y-315316D01*
X622923Y-315176D01*
X623519Y-314778D01*
X623916Y-314183D01*
X624056Y-313481D01*
X623916Y-312778D01*
X623519Y-312183D01*
X622923Y-311785D01*
X622221Y-311646D01*
D02*
G37*
G36*
X473819Y-313519D02*
X473117Y-313659D01*
X472521Y-314057D01*
X472123Y-314652D01*
X471984Y-315354D01*
X472123Y-316057D01*
X472521Y-316652D01*
X473117Y-317050D01*
X473819Y-317190D01*
X474521Y-317050D01*
X475117Y-316652D01*
X475515Y-316057D01*
X475654Y-315354D01*
X475515Y-314652D01*
X475117Y-314057D01*
X474521Y-313659D01*
X473819Y-313519D01*
D02*
G37*
G36*
X484842Y-315881D02*
X484140Y-316021D01*
X483545Y-316419D01*
X483147Y-317014D01*
X483007Y-317717D01*
X483147Y-318419D01*
X483545Y-319014D01*
X484140Y-319412D01*
X484842Y-319552D01*
X485545Y-319412D01*
X486140Y-319014D01*
X486538Y-318419D01*
X486678Y-317717D01*
X486538Y-317014D01*
X486140Y-316419D01*
X485545Y-316021D01*
X484842Y-315881D01*
D02*
G37*
G36*
X-3528Y-311844D02*
X-13402D01*
Y-321718D01*
X-3528D01*
Y-311844D01*
D02*
G37*
G36*
X556841Y-317622D02*
X555867Y-317816D01*
X555041Y-318368D01*
X554490Y-319193D01*
X554296Y-320167D01*
X554490Y-321141D01*
X555041Y-321967D01*
X555867Y-322519D01*
X556841Y-322712D01*
X557815Y-322519D01*
X558640Y-321967D01*
X559192Y-321141D01*
X559386Y-320167D01*
X559192Y-319193D01*
X558640Y-318368D01*
X557815Y-317816D01*
X556841Y-317622D01*
D02*
G37*
G36*
X541093D02*
X540119Y-317816D01*
X539293Y-318368D01*
X538742Y-319193D01*
X538548Y-320167D01*
X538742Y-321141D01*
X539293Y-321967D01*
X540119Y-322519D01*
X541093Y-322712D01*
X542067Y-322519D01*
X542893Y-321967D01*
X543444Y-321141D01*
X543638Y-320167D01*
X543444Y-319193D01*
X542893Y-318368D01*
X542067Y-317816D01*
X541093Y-317622D01*
D02*
G37*
G36*
X509597D02*
X508623Y-317816D01*
X507797Y-318368D01*
X507246Y-319193D01*
X507052Y-320167D01*
X507246Y-321141D01*
X507797Y-321967D01*
X508623Y-322519D01*
X509597Y-322712D01*
X510571Y-322519D01*
X511397Y-321967D01*
X511948Y-321141D01*
X512142Y-320167D01*
X511948Y-319193D01*
X511397Y-318368D01*
X510571Y-317816D01*
X509597Y-317622D01*
D02*
G37*
G36*
X200876Y-308685D02*
X199504Y-308820D01*
X198184Y-309221D01*
X196968Y-309871D01*
X195902Y-310745D01*
X195027Y-311811D01*
X194377Y-313027D01*
X193977Y-314347D01*
X193842Y-315719D01*
X193977Y-317091D01*
X194377Y-318411D01*
X195027Y-319627D01*
X195902Y-320693D01*
X196968Y-321567D01*
X198184Y-322217D01*
X199504Y-322618D01*
X200876Y-322753D01*
X202248Y-322618D01*
X203568Y-322217D01*
X204784Y-321567D01*
X205850Y-320693D01*
X206724Y-319627D01*
X207374Y-318411D01*
X207775Y-317091D01*
X207910Y-315719D01*
X207775Y-314347D01*
X207374Y-313027D01*
X206724Y-311811D01*
X205850Y-310745D01*
X204784Y-309871D01*
X203568Y-309221D01*
X202248Y-308820D01*
X200876Y-308685D01*
D02*
G37*
G36*
X362408Y-325006D02*
X361706Y-325146D01*
X361415Y-325340D01*
X361030Y-325508D01*
X360645Y-325340D01*
X360354Y-325146D01*
X359652Y-325006D01*
X358950Y-325146D01*
X358354Y-325543D01*
X357957Y-326139D01*
X357817Y-326841D01*
X357957Y-327544D01*
X358354Y-328139D01*
X358950Y-328537D01*
X359652Y-328677D01*
X360354Y-328537D01*
X360645Y-328343D01*
X361030Y-328174D01*
X361415Y-328343D01*
X361706Y-328537D01*
X362408Y-328677D01*
X363110Y-328537D01*
X363706Y-328139D01*
X364104Y-327544D01*
X364243Y-326841D01*
X364104Y-326139D01*
X363706Y-325543D01*
X363110Y-325146D01*
X362408Y-325006D01*
D02*
G37*
G36*
X374114Y-326199D02*
X373412Y-326339D01*
X372817Y-326736D01*
X372656D01*
X372061Y-326339D01*
X371359Y-326199D01*
X370656Y-326339D01*
X370061Y-326736D01*
X369663Y-327332D01*
X369523Y-328034D01*
X369629Y-328563D01*
X369204Y-328881D01*
X368813Y-328619D01*
X368110Y-328480D01*
X367408Y-328619D01*
X366812Y-329017D01*
X366652D01*
X366057Y-328619D01*
X365354Y-328480D01*
X364652Y-328619D01*
X364057Y-329017D01*
X363659Y-329613D01*
X363519Y-330315D01*
X363659Y-331017D01*
X364057Y-331613D01*
X364652Y-332011D01*
X365354Y-332150D01*
X366057Y-332011D01*
X366347Y-331816D01*
X366732Y-331648D01*
X367117Y-331816D01*
X367408Y-332011D01*
X368110Y-332150D01*
X368813Y-332011D01*
X369408Y-331613D01*
X369806Y-331017D01*
X369946Y-330315D01*
X369840Y-329786D01*
X370265Y-329468D01*
X370656Y-329730D01*
X371359Y-329869D01*
X372061Y-329730D01*
X372656Y-329332D01*
X372817D01*
X373412Y-329730D01*
X374114Y-329869D01*
X374817Y-329730D01*
X375412Y-329332D01*
X375810Y-328736D01*
X375950Y-328034D01*
X375810Y-327332D01*
X375412Y-326736D01*
X374817Y-326339D01*
X374114Y-326199D01*
D02*
G37*
G36*
X75768Y-314588D02*
X74395Y-314723D01*
X73076Y-315124D01*
X71860Y-315774D01*
X70794Y-316648D01*
X69919Y-317714D01*
X69269Y-318930D01*
X68869Y-320250D01*
X68734Y-321622D01*
X68869Y-322994D01*
X69269Y-324314D01*
X69919Y-325530D01*
X70794Y-326596D01*
X71860Y-327470D01*
X73076Y-328120D01*
X74395Y-328521D01*
X75768Y-328656D01*
X77140Y-328521D01*
X78459Y-328120D01*
X79676Y-327470D01*
X80741Y-326596D01*
X81616Y-325530D01*
X82266Y-324314D01*
X82666Y-322994D01*
X82802Y-321622D01*
X82666Y-320250D01*
X82266Y-318930D01*
X81616Y-317714D01*
X80741Y-316648D01*
X79676Y-315774D01*
X78459Y-315124D01*
X77140Y-314723D01*
X75768Y-314588D01*
D02*
G37*
G36*
X356299Y-328480D02*
X355597Y-328619D01*
X355001Y-329017D01*
X354841D01*
X354246Y-328619D01*
X353543Y-328480D01*
X352841Y-328619D01*
X352246Y-329017D01*
X351848Y-329613D01*
X351708Y-330315D01*
X351848Y-331017D01*
X352246Y-331613D01*
X352841Y-332011D01*
X353543Y-332150D01*
X354246Y-332011D01*
X354841Y-331613D01*
X355001D01*
X355597Y-332011D01*
X356299Y-332150D01*
X357001Y-332011D01*
X357597Y-331613D01*
X357995Y-331017D01*
X358135Y-330315D01*
X357995Y-329613D01*
X357597Y-329017D01*
X357001Y-328619D01*
X356299Y-328480D01*
D02*
G37*
G36*
X58268Y-317593D02*
X57091Y-317709D01*
X55961Y-318052D01*
X54918Y-318609D01*
X54005Y-319359D01*
X53255Y-320272D01*
X52698Y-321315D01*
X52355Y-322446D01*
X52239Y-323622D01*
X52355Y-324798D01*
X52698Y-325929D01*
X53255Y-326972D01*
X54005Y-327885D01*
X54918Y-328635D01*
X55961Y-329192D01*
X57091Y-329535D01*
X58268Y-329651D01*
X59444Y-329535D01*
X60575Y-329192D01*
X61617Y-328635D01*
X62531Y-327885D01*
X63281Y-326972D01*
X63838Y-325929D01*
X64181Y-324798D01*
X64297Y-323622D01*
X64181Y-322446D01*
X63838Y-321315D01*
X63281Y-320272D01*
X62531Y-319359D01*
X61617Y-318609D01*
X60575Y-318052D01*
X59444Y-317709D01*
X58268Y-317593D01*
D02*
G37*
G36*
X390452Y-327766D02*
X389639Y-327928D01*
X388950Y-328388D01*
X388490Y-329077D01*
X388329Y-329890D01*
X388490Y-330703D01*
X388950Y-331392D01*
X389639Y-331852D01*
X390452Y-332014D01*
X391265Y-331852D01*
X391954Y-331392D01*
X392414Y-330703D01*
X392576Y-329890D01*
X392414Y-329077D01*
X391954Y-328388D01*
X391265Y-327928D01*
X390452Y-327766D01*
D02*
G37*
G36*
X311712D02*
X310899Y-327928D01*
X310210Y-328388D01*
X309750Y-329077D01*
X309589Y-329890D01*
X309750Y-330703D01*
X310210Y-331392D01*
X310899Y-331852D01*
X311712Y-332014D01*
X312525Y-331852D01*
X313214Y-331392D01*
X313674Y-330703D01*
X313836Y-329890D01*
X313674Y-329077D01*
X313214Y-328388D01*
X312525Y-327928D01*
X311712Y-327766D01*
D02*
G37*
G36*
X209842Y-328223D02*
X208666Y-328339D01*
X207535Y-328682D01*
X206493Y-329239D01*
X205579Y-329989D01*
X204830Y-330902D01*
X204272Y-331945D01*
X204187Y-332226D01*
X203687D01*
X203602Y-331945D01*
X203045Y-330902D01*
X202295Y-329989D01*
X201381Y-329239D01*
X200339Y-328682D01*
X199208Y-328339D01*
X198031Y-328223D01*
X196855Y-328339D01*
X195724Y-328682D01*
X194682Y-329239D01*
X193768Y-329989D01*
X193018Y-330902D01*
X192461Y-331945D01*
X192376Y-332226D01*
X191876D01*
X191791Y-331945D01*
X191233Y-330902D01*
X190484Y-329989D01*
X189570Y-329239D01*
X188528Y-328682D01*
X187397Y-328339D01*
X186221Y-328223D01*
X185044Y-328339D01*
X183913Y-328682D01*
X182871Y-329239D01*
X181957Y-329989D01*
X181208Y-330902D01*
X180650Y-331945D01*
X180482Y-332501D01*
X179959D01*
X179791Y-331945D01*
X179233Y-330902D01*
X178484Y-329989D01*
X177570Y-329239D01*
X176528Y-328682D01*
X175397Y-328339D01*
X174221Y-328223D01*
X173044Y-328339D01*
X171913Y-328682D01*
X170871Y-329239D01*
X169957Y-329989D01*
X169208Y-330902D01*
X168650Y-331945D01*
X168482Y-332501D01*
X167959D01*
X167791Y-331945D01*
X167233Y-330902D01*
X166484Y-329989D01*
X165570Y-329239D01*
X164528Y-328682D01*
X163397Y-328339D01*
X162221Y-328223D01*
X161044Y-328339D01*
X159913Y-328682D01*
X158871Y-329239D01*
X157957Y-329989D01*
X157208Y-330902D01*
X156650Y-331945D01*
X156307Y-333076D01*
X156191Y-334252D01*
X156307Y-335428D01*
X156650Y-336559D01*
X157208Y-337601D01*
X157957Y-338515D01*
X158871Y-339265D01*
X159913Y-339822D01*
X161044Y-340165D01*
X162221Y-340281D01*
X163397Y-340165D01*
X164528Y-339822D01*
X165570Y-339265D01*
X166484Y-338515D01*
X167233Y-337601D01*
X167791Y-336559D01*
X167959Y-336003D01*
X168482D01*
X168650Y-336559D01*
X169208Y-337601D01*
X169957Y-338515D01*
X170871Y-339265D01*
X171913Y-339822D01*
X173044Y-340165D01*
X174221Y-340281D01*
X175397Y-340165D01*
X176528Y-339822D01*
X177570Y-339265D01*
X178484Y-338515D01*
X179233Y-337601D01*
X179791Y-336559D01*
X179959Y-336003D01*
X180482D01*
X180650Y-336559D01*
X181208Y-337601D01*
X181957Y-338515D01*
X182871Y-339265D01*
X183913Y-339822D01*
X185044Y-340165D01*
X186221Y-340281D01*
X187397Y-340165D01*
X188528Y-339822D01*
X189570Y-339265D01*
X190484Y-338515D01*
X191233Y-337601D01*
X191791Y-336559D01*
X191876Y-336278D01*
X192376D01*
X192461Y-336559D01*
X193018Y-337601D01*
X193768Y-338515D01*
X194682Y-339265D01*
X195724Y-339822D01*
X196855Y-340165D01*
X198031Y-340281D01*
X199208Y-340165D01*
X200339Y-339822D01*
X201381Y-339265D01*
X202295Y-338515D01*
X203045Y-337601D01*
X203602Y-336559D01*
X203687Y-336278D01*
X204187D01*
X204272Y-336559D01*
X204830Y-337601D01*
X205579Y-338515D01*
X206493Y-339265D01*
X207535Y-339822D01*
X208666Y-340165D01*
X209842Y-340281D01*
X211019Y-340165D01*
X212150Y-339822D01*
X213192Y-339265D01*
X214106Y-338515D01*
X214856Y-337601D01*
X215413Y-336559D01*
X215756Y-335428D01*
X215872Y-334252D01*
X215756Y-333076D01*
X215413Y-331945D01*
X214856Y-330902D01*
X214106Y-329989D01*
X213192Y-329239D01*
X212150Y-328682D01*
X211019Y-328339D01*
X209842Y-328223D01*
D02*
G37*
G36*
X622677Y-331472D02*
X621975Y-331611D01*
X621379Y-332009D01*
X620982Y-332605D01*
X620842Y-333307D01*
X620982Y-334009D01*
X621379Y-334605D01*
X621975Y-335003D01*
X622677Y-335142D01*
X623380Y-335003D01*
X623975Y-334605D01*
X624373Y-334009D01*
X624512Y-333307D01*
X624373Y-332605D01*
X623975Y-332009D01*
X623380Y-331611D01*
X622677Y-331472D01*
D02*
G37*
G36*
X598959D02*
X598257Y-331611D01*
X597662Y-332009D01*
X597264Y-332605D01*
X597124Y-333307D01*
X597264Y-334009D01*
X597662Y-334605D01*
X598257Y-335003D01*
X598959Y-335142D01*
X599662Y-335003D01*
X600257Y-334605D01*
X600655Y-334009D01*
X600795Y-333307D01*
X600655Y-332605D01*
X600257Y-332009D01*
X599662Y-331611D01*
X598959Y-331472D01*
D02*
G37*
G36*
X552756Y-333992D02*
X552054Y-334131D01*
X551458Y-334529D01*
X551060Y-335124D01*
X550921Y-335827D01*
X551060Y-336529D01*
X551458Y-337124D01*
X552054Y-337522D01*
X552756Y-337662D01*
X553458Y-337522D01*
X554054Y-337124D01*
X554452Y-336529D01*
X554591Y-335827D01*
X554452Y-335124D01*
X554054Y-334529D01*
X553458Y-334131D01*
X552756Y-333992D01*
D02*
G37*
G36*
X505410Y-334201D02*
X504708Y-334341D01*
X504112Y-334739D01*
X503715Y-335334D01*
X503575Y-336036D01*
X503715Y-336739D01*
X504112Y-337334D01*
X504708Y-337732D01*
X505410Y-337872D01*
X506112Y-337732D01*
X506708Y-337334D01*
X507106Y-336739D01*
X507245Y-336036D01*
X507106Y-335334D01*
X506708Y-334739D01*
X506112Y-334341D01*
X505410Y-334201D01*
D02*
G37*
G36*
X544882Y-334385D02*
X544180Y-334525D01*
X543584Y-334923D01*
X543186Y-335518D01*
X543047Y-336221D01*
X543186Y-336923D01*
X543584Y-337518D01*
X544180Y-337916D01*
X544882Y-338056D01*
X545584Y-337916D01*
X546180Y-337518D01*
X546578Y-336923D01*
X546717Y-336221D01*
X546578Y-335518D01*
X546180Y-334923D01*
X545584Y-334525D01*
X544882Y-334385D01*
D02*
G37*
G36*
X521654D02*
X520951Y-334525D01*
X520356Y-334923D01*
X519958Y-335518D01*
X519818Y-336221D01*
X519958Y-336923D01*
X520356Y-337518D01*
X520951Y-337916D01*
X521654Y-338056D01*
X522356Y-337916D01*
X522951Y-337518D01*
X523349Y-336923D01*
X523489Y-336221D01*
X523349Y-335518D01*
X522951Y-334923D01*
X522356Y-334525D01*
X521654Y-334385D01*
D02*
G37*
G36*
X513386D02*
X512683Y-334525D01*
X512088Y-334923D01*
X511690Y-335518D01*
X511551Y-336221D01*
X511690Y-336923D01*
X512088Y-337518D01*
X512683Y-337916D01*
X513386Y-338056D01*
X514088Y-337916D01*
X514684Y-337518D01*
X515081Y-336923D01*
X515221Y-336221D01*
X515081Y-335518D01*
X514684Y-334923D01*
X514088Y-334525D01*
X513386Y-334385D01*
D02*
G37*
G36*
X27559Y-335566D02*
X26857Y-335706D01*
X26261Y-336104D01*
X25864Y-336699D01*
X25724Y-337402D01*
X25864Y-338104D01*
X26261Y-338699D01*
X26857Y-339097D01*
X27559Y-339237D01*
X28261Y-339097D01*
X28857Y-338699D01*
X29255Y-338104D01*
X29394Y-337402D01*
X29255Y-336699D01*
X28857Y-336104D01*
X28261Y-335706D01*
X27559Y-335566D01*
D02*
G37*
G36*
X530315Y-337141D02*
X529613Y-337281D01*
X529017Y-337679D01*
X528619Y-338274D01*
X528480Y-338976D01*
X528619Y-339679D01*
X529017Y-340274D01*
X529613Y-340672D01*
X530315Y-340812D01*
X531017Y-340672D01*
X531613Y-340274D01*
X532011Y-339679D01*
X532150Y-338976D01*
X532011Y-338274D01*
X531613Y-337679D01*
X531017Y-337281D01*
X530315Y-337141D01*
D02*
G37*
G36*
X453193Y-327117D02*
X451839Y-327251D01*
X450537Y-327646D01*
X449338Y-328287D01*
X448286Y-329150D01*
X447423Y-330201D01*
X446782Y-331401D01*
X446387Y-332703D01*
X446254Y-334056D01*
X446387Y-335410D01*
X446782Y-336712D01*
X447423Y-337912D01*
X448286Y-338963D01*
X449338Y-339826D01*
X450537Y-340467D01*
X451839Y-340862D01*
X453193Y-340995D01*
X454546Y-340862D01*
X455848Y-340467D01*
X457048Y-339826D01*
X458099Y-338963D01*
X458962Y-337912D01*
X459604Y-336712D01*
X459998Y-335410D01*
X460132Y-334056D01*
X459998Y-332703D01*
X459604Y-331401D01*
X458962Y-330201D01*
X458099Y-329150D01*
X457048Y-328287D01*
X455848Y-327646D01*
X454546Y-327251D01*
X453193Y-327117D01*
D02*
G37*
G36*
X256693D02*
X255339Y-327251D01*
X254037Y-327646D01*
X252838Y-328287D01*
X251786Y-329150D01*
X250923Y-330201D01*
X250282Y-331401D01*
X249887Y-332703D01*
X249754Y-334056D01*
X249887Y-335410D01*
X250282Y-336712D01*
X250923Y-337912D01*
X251786Y-338963D01*
X252838Y-339826D01*
X254037Y-340467D01*
X255339Y-340862D01*
X256693Y-340995D01*
X258047Y-340862D01*
X259348Y-340467D01*
X260548Y-339826D01*
X261599Y-338963D01*
X262462Y-337912D01*
X263104Y-336712D01*
X263498Y-335410D01*
X263632Y-334056D01*
X263498Y-332703D01*
X263104Y-331401D01*
X262462Y-330201D01*
X261599Y-329150D01*
X260548Y-328287D01*
X259348Y-327646D01*
X258047Y-327251D01*
X256693Y-327117D01*
D02*
G37*
G36*
X561024Y-338322D02*
X560321Y-338462D01*
X559726Y-338860D01*
X559328Y-339455D01*
X559188Y-340158D01*
X559328Y-340860D01*
X559726Y-341455D01*
X560321Y-341853D01*
X561024Y-341993D01*
X561726Y-341853D01*
X562321Y-341455D01*
X562719Y-340860D01*
X562859Y-340158D01*
X562719Y-339455D01*
X562321Y-338860D01*
X561726Y-338462D01*
X561024Y-338322D01*
D02*
G37*
G36*
X582058Y-320039D02*
X580331Y-320175D01*
X578648Y-320579D01*
X577048Y-321241D01*
X575572Y-322146D01*
X574255Y-323271D01*
X573131Y-324587D01*
X572226Y-326063D01*
X571564Y-327663D01*
X571159Y-329347D01*
X571024Y-331073D01*
X571159Y-332799D01*
X571564Y-334483D01*
X572226Y-336082D01*
X573131Y-337559D01*
X574255Y-338875D01*
X575572Y-340000D01*
X577048Y-340904D01*
X578648Y-341567D01*
X580331Y-341971D01*
X582058Y-342107D01*
X583784Y-341971D01*
X585467Y-341567D01*
X587067Y-340904D01*
X588543Y-340000D01*
X589860Y-338875D01*
X590984Y-337559D01*
X591889Y-336082D01*
X592552Y-334483D01*
X592956Y-332799D01*
X593091Y-331073D01*
X592956Y-329347D01*
X592552Y-327663D01*
X591889Y-326063D01*
X590984Y-324587D01*
X589860Y-323271D01*
X588543Y-322146D01*
X587067Y-321241D01*
X585467Y-320579D01*
X583784Y-320175D01*
X582058Y-320039D01*
D02*
G37*
G36*
X479695D02*
X477969Y-320175D01*
X476286Y-320579D01*
X474686Y-321241D01*
X473210Y-322146D01*
X471893Y-323271D01*
X470769Y-324587D01*
X469864Y-326063D01*
X469201Y-327663D01*
X468797Y-329347D01*
X468661Y-331073D01*
X468797Y-332799D01*
X469201Y-334483D01*
X469864Y-336082D01*
X470769Y-337559D01*
X471893Y-338875D01*
X473210Y-340000D01*
X474686Y-340904D01*
X476286Y-341567D01*
X477969Y-341971D01*
X479695Y-342107D01*
X481421Y-341971D01*
X483105Y-341567D01*
X484705Y-340904D01*
X486181Y-340000D01*
X487498Y-338875D01*
X488622Y-337559D01*
X489527Y-336082D01*
X490189Y-334483D01*
X490593Y-332799D01*
X490729Y-331073D01*
X490593Y-329347D01*
X490189Y-327663D01*
X489527Y-326063D01*
X488622Y-324587D01*
X487498Y-323271D01*
X486181Y-322146D01*
X484705Y-321241D01*
X483105Y-320579D01*
X481421Y-320175D01*
X479695Y-320039D01*
D02*
G37*
G36*
X540551Y-339110D02*
X539849Y-339249D01*
X539254Y-339647D01*
X538856Y-340243D01*
X538716Y-340945D01*
X538856Y-341647D01*
X539254Y-342243D01*
X539849Y-342640D01*
X540551Y-342780D01*
X541254Y-342640D01*
X541849Y-342243D01*
X542247Y-341647D01*
X542386Y-340945D01*
X542247Y-340243D01*
X541849Y-339647D01*
X541254Y-339249D01*
X540551Y-339110D01*
D02*
G37*
G36*
X-23622Y-333795D02*
X-24324Y-333934D01*
X-24920Y-334332D01*
X-25318Y-334928D01*
X-25457Y-335630D01*
X-25318Y-336332D01*
X-24920Y-336928D01*
X-24324Y-337326D01*
X-24234Y-337344D01*
Y-337853D01*
X-24324Y-337871D01*
X-24920Y-338269D01*
X-25318Y-338865D01*
X-25457Y-339567D01*
X-25318Y-340269D01*
X-25032Y-340696D01*
X-24958Y-341043D01*
X-25032Y-341391D01*
X-25318Y-341817D01*
X-25457Y-342520D01*
X-25318Y-343222D01*
X-24920Y-343817D01*
X-24324Y-344215D01*
X-23622Y-344355D01*
X-22920Y-344215D01*
X-22324Y-343817D01*
X-21926Y-343222D01*
X-21787Y-342520D01*
X-21926Y-341817D01*
X-22212Y-341391D01*
X-22286Y-341043D01*
X-22212Y-340696D01*
X-21926Y-340269D01*
X-21787Y-339567D01*
X-21926Y-338865D01*
X-22324Y-338269D01*
X-22920Y-337871D01*
X-23010Y-337853D01*
Y-337344D01*
X-22920Y-337326D01*
X-22324Y-336928D01*
X-21926Y-336332D01*
X-21787Y-335630D01*
X-21926Y-334928D01*
X-22324Y-334332D01*
X-22920Y-333934D01*
X-23622Y-333795D01*
D02*
G37*
G36*
X380807Y-344309D02*
X380105Y-344449D01*
X379542Y-344825D01*
X379396Y-344887D01*
X379069D01*
X378923Y-344825D01*
X378360Y-344449D01*
X377658Y-344309D01*
X376956Y-344449D01*
X376360Y-344847D01*
X376187Y-345106D01*
X375585D01*
X375412Y-344847D01*
X374817Y-344449D01*
X374114Y-344309D01*
X373412Y-344449D01*
X372817Y-344847D01*
X372656D01*
X372061Y-344449D01*
X371359Y-344309D01*
X370656Y-344449D01*
X370061Y-344847D01*
X369663Y-345442D01*
X369645Y-345533D01*
X369135D01*
X369117Y-345442D01*
X368719Y-344847D01*
X368124Y-344449D01*
X367422Y-344309D01*
X366719Y-344449D01*
X366429Y-344643D01*
X366044Y-344812D01*
X365659Y-344643D01*
X365368Y-344449D01*
X364666Y-344309D01*
X363963Y-344449D01*
X363368Y-344847D01*
X362970Y-345442D01*
X362952Y-345533D01*
X362442D01*
X362424Y-345442D01*
X362026Y-344847D01*
X361431Y-344449D01*
X360729Y-344309D01*
X360026Y-344449D01*
X359431Y-344847D01*
X359270D01*
X358675Y-344449D01*
X357973Y-344309D01*
X357270Y-344449D01*
X356675Y-344847D01*
X356277Y-345442D01*
X356259Y-345533D01*
X355749D01*
X355731Y-345442D01*
X355333Y-344847D01*
X354738Y-344449D01*
X354036Y-344309D01*
X353333Y-344449D01*
X352738Y-344847D01*
X352577D01*
X351982Y-344449D01*
X351280Y-344309D01*
X350577Y-344449D01*
X349982Y-344847D01*
X349584Y-345442D01*
X349445Y-346144D01*
X349584Y-346847D01*
X349982Y-347442D01*
X350577Y-347840D01*
X351280Y-347980D01*
X351982Y-347840D01*
X352577Y-347442D01*
X352738D01*
X353333Y-347840D01*
X354036Y-347980D01*
X354738Y-347840D01*
X355333Y-347442D01*
X355731Y-346847D01*
X355749Y-346756D01*
X356259D01*
X356277Y-346847D01*
X356675Y-347442D01*
X357270Y-347840D01*
X357973Y-347980D01*
X358675Y-347840D01*
X359270Y-347442D01*
X359431D01*
X360026Y-347840D01*
X360729Y-347980D01*
X361431Y-347840D01*
X362026Y-347442D01*
X362424Y-346847D01*
X362442Y-346756D01*
X362952D01*
X362970Y-346847D01*
X363368Y-347442D01*
X363963Y-347840D01*
X364666Y-347980D01*
X365368Y-347840D01*
X365659Y-347646D01*
X366044Y-347477D01*
X366429Y-347646D01*
X366719Y-347840D01*
X367422Y-347980D01*
X368124Y-347840D01*
X368719Y-347442D01*
X369117Y-346847D01*
X369135Y-346756D01*
X369645D01*
X369663Y-346847D01*
X370061Y-347442D01*
X370656Y-347840D01*
X371359Y-347980D01*
X372061Y-347840D01*
X372656Y-347442D01*
X372817D01*
X373412Y-347840D01*
X374114Y-347980D01*
X374817Y-347840D01*
X375412Y-347442D01*
X375585Y-347183D01*
X376187D01*
X376360Y-347442D01*
X376956Y-347840D01*
X377658Y-347980D01*
X378360Y-347840D01*
X378923Y-347464D01*
X379069Y-347402D01*
X379396D01*
X379542Y-347464D01*
X380105Y-347840D01*
X380807Y-347980D01*
X381510Y-347840D01*
X382105Y-347442D01*
X382503Y-346847D01*
X382643Y-346144D01*
X382503Y-345442D01*
X382105Y-344847D01*
X381510Y-344449D01*
X380807Y-344309D01*
D02*
G37*
G36*
X623228Y-341472D02*
X622526Y-341612D01*
X621931Y-342009D01*
X621533Y-342605D01*
X621393Y-343307D01*
X621533Y-344009D01*
X621931Y-344605D01*
X622526Y-345003D01*
X623228Y-345142D01*
X623931Y-345003D01*
X624526Y-344605D01*
X624924Y-344009D01*
X625064Y-343307D01*
X624924Y-342605D01*
X624526Y-342009D01*
X623931Y-341612D01*
X623228Y-341472D01*
D02*
G37*
G36*
X598819D02*
X598117Y-341612D01*
X597521Y-342009D01*
X597123Y-342605D01*
X596984Y-343307D01*
X597123Y-344009D01*
X597521Y-344605D01*
X598117Y-345003D01*
X598819Y-345142D01*
X599521Y-345003D01*
X600117Y-344605D01*
X600515Y-344009D01*
X600654Y-343307D01*
X600515Y-342605D01*
X600117Y-342009D01*
X599521Y-341612D01*
X598819Y-341472D01*
D02*
G37*
G36*
X4331Y-342653D02*
X3628Y-342793D01*
X3033Y-343191D01*
X2635Y-343786D01*
X2495Y-344488D01*
X2635Y-345191D01*
X3033Y-345786D01*
X3628Y-346184D01*
X4331Y-346323D01*
X5033Y-346184D01*
X5628Y-345786D01*
X6026Y-345191D01*
X6166Y-344488D01*
X6026Y-343786D01*
X5628Y-343191D01*
X5033Y-342793D01*
X4331Y-342653D01*
D02*
G37*
G36*
X29543Y-343379D02*
X28841Y-343519D01*
X28245Y-343917D01*
X27847Y-344512D01*
X27708Y-345214D01*
X27847Y-345917D01*
X28245Y-346512D01*
X28841Y-346910D01*
X29543Y-347050D01*
X30245Y-346910D01*
X30841Y-346512D01*
X31238Y-345917D01*
X31378Y-345214D01*
X31238Y-344512D01*
X30841Y-343917D01*
X30245Y-343519D01*
X29543Y-343379D01*
D02*
G37*
G36*
X142126Y-346196D02*
X141424Y-346336D01*
X140828Y-346734D01*
X140430Y-347329D01*
X140291Y-348031D01*
X140430Y-348734D01*
X140828Y-349329D01*
X141424Y-349727D01*
X142126Y-349867D01*
X142828Y-349727D01*
X143424Y-349329D01*
X143822Y-348734D01*
X143961Y-348031D01*
X143822Y-347329D01*
X143424Y-346734D01*
X142828Y-346336D01*
X142126Y-346196D01*
D02*
G37*
G36*
X26772Y-346984D02*
X26069Y-347123D01*
X25474Y-347521D01*
X25076Y-348117D01*
X24936Y-348819D01*
X25076Y-349521D01*
X25474Y-350117D01*
X26069Y-350515D01*
X26772Y-350654D01*
X27474Y-350515D01*
X28069Y-350117D01*
X28467Y-349521D01*
X28607Y-348819D01*
X28467Y-348117D01*
X28069Y-347521D01*
X27474Y-347123D01*
X26772Y-346984D01*
D02*
G37*
G36*
X12598Y-347377D02*
X11896Y-347517D01*
X11301Y-347915D01*
X10903Y-348510D01*
X10763Y-349213D01*
X10903Y-349915D01*
X11301Y-350510D01*
X11896Y-350908D01*
X12598Y-351048D01*
X13301Y-350908D01*
X13896Y-350510D01*
X14294Y-349915D01*
X14434Y-349213D01*
X14294Y-348510D01*
X13896Y-347915D01*
X13301Y-347517D01*
X12598Y-347377D01*
D02*
G37*
G36*
X-18601Y-347574D02*
X-19304Y-347714D01*
X-19899Y-348112D01*
X-20297Y-348707D01*
X-20437Y-349409D01*
X-20297Y-350112D01*
X-19899Y-350707D01*
X-19304Y-351105D01*
X-18601Y-351244D01*
X-17899Y-351105D01*
X-17304Y-350707D01*
X-16906Y-350112D01*
X-16766Y-349409D01*
X-16906Y-348707D01*
X-17304Y-348112D01*
X-17899Y-347714D01*
X-18601Y-347574D01*
D02*
G37*
G36*
X141587Y-350326D02*
X140885Y-350466D01*
X140290Y-350864D01*
X139892Y-351459D01*
X139752Y-352161D01*
X139892Y-352864D01*
X140290Y-353459D01*
X140885Y-353857D01*
X141587Y-353997D01*
X142290Y-353857D01*
X142885Y-353459D01*
X143283Y-352864D01*
X143423Y-352161D01*
X143283Y-351459D01*
X142885Y-350864D01*
X142290Y-350466D01*
X141587Y-350326D01*
D02*
G37*
G36*
X-1181Y-350995D02*
X-1883Y-351135D01*
X-2479Y-351533D01*
X-2877Y-352128D01*
X-3016Y-352831D01*
X-2877Y-353533D01*
X-2479Y-354129D01*
X-1883Y-354526D01*
X-1181Y-354666D01*
X-479Y-354526D01*
X117Y-354129D01*
X514Y-353533D01*
X654Y-352831D01*
X514Y-352128D01*
X117Y-351533D01*
X-479Y-351135D01*
X-1181Y-350995D01*
D02*
G37*
G36*
X622753Y-351472D02*
X622051Y-351611D01*
X621456Y-352009D01*
X621058Y-352605D01*
X620918Y-353307D01*
X621058Y-354009D01*
X621456Y-354605D01*
X622051Y-355003D01*
X622753Y-355142D01*
X623456Y-355003D01*
X624051Y-354605D01*
X624449Y-354009D01*
X624589Y-353307D01*
X624449Y-352605D01*
X624051Y-352009D01*
X623456Y-351611D01*
X622753Y-351472D01*
D02*
G37*
G36*
X157480Y-356826D02*
X156778Y-356966D01*
X156496Y-357154D01*
X156214Y-356966D01*
X155512Y-356826D01*
X154809Y-356966D01*
X154528Y-357154D01*
X154246Y-356966D01*
X153543Y-356826D01*
X152841Y-356966D01*
X152246Y-357364D01*
X151848Y-357959D01*
X151708Y-358661D01*
X151848Y-359364D01*
X152246Y-359959D01*
X152286Y-359986D01*
Y-360486D01*
X152246Y-360513D01*
X151848Y-361109D01*
X151708Y-361811D01*
X151848Y-362513D01*
X152246Y-363109D01*
X152841Y-363507D01*
X153543Y-363646D01*
X154246Y-363507D01*
X154528Y-363318D01*
X154809Y-363507D01*
X155512Y-363646D01*
X156214Y-363507D01*
X156496Y-363318D01*
X156778Y-363507D01*
X157480Y-363646D01*
X158183Y-363507D01*
X158778Y-363109D01*
X159176Y-362513D01*
X159316Y-361811D01*
X159176Y-361109D01*
X158778Y-360513D01*
X158738Y-360486D01*
Y-359986D01*
X158778Y-359959D01*
X159176Y-359364D01*
X159316Y-358661D01*
X159176Y-357959D01*
X158778Y-357364D01*
X158183Y-356966D01*
X157480Y-356826D01*
D02*
G37*
G36*
X449150Y-353997D02*
X448448Y-354137D01*
X447853Y-354535D01*
X447455Y-355130D01*
X447315Y-355832D01*
X447455Y-356535D01*
X447853Y-357130D01*
X448448Y-357528D01*
X449150Y-357668D01*
X449853Y-357528D01*
X450448Y-357130D01*
X450846Y-356535D01*
X450985Y-355832D01*
X450846Y-355130D01*
X450448Y-354535D01*
X449853Y-354137D01*
X449150Y-353997D01*
D02*
G37*
G36*
X561330Y-354264D02*
X560628Y-354404D01*
X560032Y-354802D01*
X559635Y-355397D01*
X559495Y-356099D01*
X559635Y-356802D01*
X560032Y-357397D01*
X560628Y-357795D01*
X561330Y-357935D01*
X562032Y-357795D01*
X562628Y-357397D01*
X563026Y-356802D01*
X563165Y-356099D01*
X563026Y-355397D01*
X562628Y-354802D01*
X562032Y-354404D01*
X561330Y-354264D01*
D02*
G37*
G36*
X533931Y-354461D02*
X533228Y-354601D01*
X532633Y-354999D01*
X532235Y-355594D01*
X532095Y-356296D01*
X532235Y-356999D01*
X532633Y-357594D01*
X533228Y-357992D01*
X533931Y-358132D01*
X534633Y-357992D01*
X535228Y-357594D01*
X535626Y-356999D01*
X535766Y-356296D01*
X535626Y-355594D01*
X535228Y-354999D01*
X534633Y-354601D01*
X533931Y-354461D01*
D02*
G37*
G36*
X493234Y-354784D02*
X492532Y-354924D01*
X491936Y-355322D01*
X491538Y-355918D01*
X491399Y-356620D01*
X491538Y-357322D01*
X491936Y-357917D01*
X492532Y-358315D01*
X493234Y-358455D01*
X493936Y-358315D01*
X494532Y-357917D01*
X494930Y-357322D01*
X495069Y-356620D01*
X494930Y-355918D01*
X494532Y-355322D01*
X493936Y-354924D01*
X493234Y-354784D01*
D02*
G37*
G36*
X579072Y-354855D02*
X578370Y-354994D01*
X577774Y-355392D01*
X577376Y-355988D01*
X577237Y-356690D01*
X577376Y-357392D01*
X577774Y-357988D01*
X578370Y-358385D01*
X579072Y-358525D01*
X579774Y-358385D01*
X580370Y-357988D01*
X580767Y-357392D01*
X580907Y-356690D01*
X580767Y-355988D01*
X580370Y-355392D01*
X579774Y-354994D01*
X579072Y-354855D01*
D02*
G37*
G36*
X415623Y-356556D02*
X414920Y-356696D01*
X414325Y-357094D01*
X413927Y-357689D01*
X413788Y-358391D01*
X413927Y-359094D01*
X414325Y-359689D01*
X414920Y-360087D01*
X415623Y-360227D01*
X416325Y-360087D01*
X416921Y-359689D01*
X417318Y-359094D01*
X417458Y-358391D01*
X417318Y-357689D01*
X416921Y-357094D01*
X416325Y-356696D01*
X415623Y-356556D01*
D02*
G37*
G36*
X543698Y-356823D02*
X542996Y-356963D01*
X542400Y-357361D01*
X542002Y-357956D01*
X541863Y-358659D01*
X542002Y-359361D01*
X542400Y-359956D01*
X542996Y-360354D01*
X543698Y-360494D01*
X544400Y-360354D01*
X544996Y-359956D01*
X545393Y-359361D01*
X545533Y-358659D01*
X545393Y-357956D01*
X544996Y-357361D01*
X544400Y-356963D01*
X543698Y-356823D01*
D02*
G37*
G36*
X499525Y-357020D02*
X498823Y-357160D01*
X498228Y-357558D01*
X497830Y-358153D01*
X497690Y-358855D01*
X497830Y-359558D01*
X498228Y-360153D01*
X498823Y-360551D01*
X499525Y-360691D01*
X500228Y-360551D01*
X500823Y-360153D01*
X501221Y-359558D01*
X501361Y-358855D01*
X501221Y-358153D01*
X500823Y-357558D01*
X500228Y-357160D01*
X499525Y-357020D01*
D02*
G37*
G36*
X460678Y-357344D02*
X459975Y-357483D01*
X459380Y-357881D01*
X458982Y-358476D01*
X458842Y-359179D01*
X458982Y-359881D01*
X459380Y-360477D01*
X459975Y-360874D01*
X460678Y-361014D01*
X461380Y-360874D01*
X461975Y-360477D01*
X462373Y-359881D01*
X462513Y-359179D01*
X462373Y-358476D01*
X461975Y-357881D01*
X461380Y-357483D01*
X460678Y-357344D01*
D02*
G37*
G36*
X198392Y-365007D02*
X197690Y-365146D01*
X197094Y-365544D01*
X196697Y-366140D01*
X196557Y-366842D01*
X196697Y-367544D01*
X197094Y-368140D01*
X197343Y-368306D01*
X197148Y-368777D01*
X196701Y-368688D01*
X195999Y-368828D01*
X195403Y-369225D01*
X195005Y-369821D01*
X194866Y-370523D01*
X195005Y-371225D01*
X195403Y-371821D01*
X195999Y-372219D01*
X196701Y-372358D01*
X197403Y-372219D01*
X197998Y-371821D01*
X198396Y-371225D01*
X198536Y-370523D01*
X198396Y-369821D01*
X197998Y-369225D01*
X197750Y-369059D01*
X197945Y-368588D01*
X198392Y-368677D01*
X199094Y-368537D01*
X199690Y-368140D01*
X200088Y-367544D01*
X200227Y-366842D01*
X200088Y-366140D01*
X199690Y-365544D01*
X199094Y-365146D01*
X198392Y-365007D01*
D02*
G37*
G36*
X241929Y-372820D02*
X241227Y-372960D01*
X240631Y-373357D01*
X240234Y-373953D01*
X240215Y-374043D01*
X239706D01*
X239688Y-373953D01*
X239290Y-373357D01*
X238695Y-372960D01*
X237992Y-372820D01*
X237290Y-372960D01*
X236694Y-373357D01*
X236297Y-373953D01*
X236157Y-374655D01*
X236297Y-375357D01*
X236694Y-375953D01*
X237290Y-376351D01*
X237992Y-376490D01*
X238695Y-376351D01*
X239290Y-375953D01*
X239688Y-375357D01*
X239706Y-375267D01*
X240215D01*
X240234Y-375357D01*
X240631Y-375953D01*
X241227Y-376351D01*
X241929Y-376490D01*
X242632Y-376351D01*
X243227Y-375953D01*
X243625Y-375357D01*
X243764Y-374655D01*
X243625Y-373953D01*
X243227Y-373357D01*
X242632Y-372960D01*
X241929Y-372820D01*
D02*
G37*
G36*
X210433D02*
X209731Y-372960D01*
X209135Y-373357D01*
X208737Y-373953D01*
X208719Y-374043D01*
X208210D01*
X208192Y-373953D01*
X207794Y-373357D01*
X207198Y-372960D01*
X206496Y-372820D01*
X205794Y-372960D01*
X205198Y-373357D01*
X204801Y-373953D01*
X204661Y-374655D01*
X204801Y-375357D01*
X205198Y-375953D01*
X205794Y-376351D01*
X206496Y-376490D01*
X207198Y-376351D01*
X207794Y-375953D01*
X208192Y-375357D01*
X208210Y-375267D01*
X208719D01*
X208737Y-375357D01*
X209135Y-375953D01*
X209731Y-376351D01*
X210433Y-376490D01*
X211135Y-376351D01*
X211731Y-375953D01*
X212129Y-375357D01*
X212268Y-374655D01*
X212129Y-373953D01*
X211731Y-373357D01*
X211135Y-372960D01*
X210433Y-372820D01*
D02*
G37*
G36*
X218445Y-372272D02*
X217743Y-372412D01*
X217147Y-372810D01*
X216749Y-373405D01*
X216610Y-374108D01*
X216749Y-374810D01*
X217147Y-375405D01*
X217743Y-375803D01*
X218445Y-375943D01*
X219147Y-375803D01*
X219743Y-375405D01*
X220141Y-374810D01*
X220280Y-374108D01*
X220141Y-373405D01*
X219743Y-372810D01*
X219147Y-372412D01*
X218445Y-372272D01*
D02*
G37*
G36*
X269502Y-372456D02*
X268800Y-372595D01*
X268205Y-372993D01*
X267807Y-373589D01*
X267667Y-374291D01*
X267807Y-374993D01*
X268205Y-375589D01*
X268800Y-375987D01*
X269502Y-376126D01*
X270205Y-375987D01*
X270800Y-375589D01*
X271159Y-375051D01*
X271393Y-375038D01*
X271679Y-375104D01*
X271730Y-375357D01*
X272128Y-375953D01*
X272723Y-376351D01*
X273425Y-376490D01*
X274128Y-376351D01*
X274723Y-375953D01*
X275121Y-375357D01*
X275260Y-374655D01*
X275121Y-373953D01*
X274723Y-373357D01*
X274128Y-372960D01*
X273425Y-372820D01*
X272723Y-372960D01*
X272128Y-373357D01*
X271769Y-373895D01*
X271535Y-373908D01*
X271248Y-373842D01*
X271198Y-373589D01*
X270800Y-372993D01*
X270205Y-372595D01*
X269502Y-372456D01*
D02*
G37*
G36*
X253655Y-372586D02*
X252953Y-372726D01*
X252357Y-373123D01*
X251959Y-373719D01*
X251820Y-374421D01*
X251959Y-375123D01*
X252357Y-375719D01*
X252953Y-376117D01*
X253655Y-376256D01*
X254357Y-376117D01*
X254953Y-375719D01*
X255436D01*
X255592Y-375953D01*
X256187Y-376351D01*
X256890Y-376490D01*
X257592Y-376351D01*
X258188Y-375953D01*
X258585Y-375357D01*
X258725Y-374655D01*
X258585Y-373953D01*
X258188Y-373357D01*
X257592Y-372960D01*
X256890Y-372820D01*
X256187Y-372960D01*
X255592Y-373357D01*
X255109D01*
X254953Y-373123D01*
X254357Y-372726D01*
X253655Y-372586D01*
D02*
G37*
G36*
X222638Y-372820D02*
X221936Y-372960D01*
X221340Y-373357D01*
X220942Y-373953D01*
X220802Y-374655D01*
X220942Y-375357D01*
X221340Y-375953D01*
X221936Y-376351D01*
X222638Y-376490D01*
X223340Y-376351D01*
X223936Y-375953D01*
X224333Y-375357D01*
X224473Y-374655D01*
X224333Y-373953D01*
X223936Y-373357D01*
X223340Y-372960D01*
X222638Y-372820D01*
D02*
G37*
G36*
X190354Y-375576D02*
X189652Y-375715D01*
X189057Y-376113D01*
X188659Y-376709D01*
X188519Y-377411D01*
X188659Y-378113D01*
X189057Y-378709D01*
X189652Y-379107D01*
X190354Y-379246D01*
X191057Y-379107D01*
X191652Y-378709D01*
X192050Y-378113D01*
X192190Y-377411D01*
X192050Y-376709D01*
X191652Y-376113D01*
X191057Y-375715D01*
X190354Y-375576D01*
D02*
G37*
G36*
X178543D02*
X177841Y-375715D01*
X177246Y-376113D01*
X176848Y-376709D01*
X176708Y-377411D01*
X176848Y-378113D01*
X177246Y-378709D01*
X177841Y-379107D01*
X178543Y-379246D01*
X179246Y-379107D01*
X179841Y-378709D01*
X180239Y-378113D01*
X180379Y-377411D01*
X180239Y-376709D01*
X179841Y-376113D01*
X179246Y-375715D01*
X178543Y-375576D01*
D02*
G37*
G36*
X158661Y-384631D02*
X157959Y-384771D01*
X157677Y-384959D01*
X157395Y-384771D01*
X156693Y-384631D01*
X155991Y-384771D01*
X155709Y-384959D01*
X155427Y-384771D01*
X154724Y-384631D01*
X154022Y-384771D01*
X153427Y-385168D01*
X153029Y-385764D01*
X152889Y-386466D01*
X153029Y-387169D01*
X153427Y-387764D01*
X153467Y-387791D01*
Y-388291D01*
X153427Y-388318D01*
X153029Y-388913D01*
X152889Y-389616D01*
X153029Y-390318D01*
X153427Y-390914D01*
X154022Y-391311D01*
X154724Y-391451D01*
X155427Y-391311D01*
X155709Y-391123D01*
X155991Y-391311D01*
X156693Y-391451D01*
X157395Y-391311D01*
X157677Y-391123D01*
X157959Y-391311D01*
X158661Y-391451D01*
X159364Y-391311D01*
X159959Y-390914D01*
X160357Y-390318D01*
X160497Y-389616D01*
X160357Y-388913D01*
X159959Y-388318D01*
X159919Y-388291D01*
Y-387791D01*
X159959Y-387764D01*
X160357Y-387169D01*
X160497Y-386466D01*
X160357Y-385764D01*
X159959Y-385168D01*
X159364Y-384771D01*
X158661Y-384631D01*
D02*
G37*
G36*
X232480Y-385418D02*
X231778Y-385558D01*
X231215Y-385934D01*
X231069Y-385996D01*
X230743D01*
X230596Y-385934D01*
X230033Y-385558D01*
X229331Y-385418D01*
X228628Y-385558D01*
X228033Y-385956D01*
X227635Y-386551D01*
X227496Y-387253D01*
X227635Y-387956D01*
X228033Y-388551D01*
X228628Y-388949D01*
X229331Y-389089D01*
X230033Y-388949D01*
X230596Y-388573D01*
X230743Y-388511D01*
X231069D01*
X231215Y-388573D01*
X231778Y-388949D01*
X232480Y-389089D01*
X233183Y-388949D01*
X233778Y-388551D01*
X234176Y-387956D01*
X234316Y-387253D01*
X234176Y-386551D01*
X233778Y-385956D01*
X233183Y-385558D01*
X232480Y-385418D01*
D02*
G37*
G36*
X215945D02*
X215243Y-385558D01*
X214680Y-385934D01*
X214533Y-385996D01*
X214207D01*
X214060Y-385934D01*
X213498Y-385558D01*
X212795Y-385418D01*
X212093Y-385558D01*
X211498Y-385956D01*
X211100Y-386551D01*
X210960Y-387253D01*
X211100Y-387956D01*
X211498Y-388551D01*
X212093Y-388949D01*
X212795Y-389089D01*
X213498Y-388949D01*
X214060Y-388573D01*
X214207Y-388511D01*
X214533D01*
X214680Y-388573D01*
X215243Y-388949D01*
X215945Y-389089D01*
X216647Y-388949D01*
X217243Y-388551D01*
X217640Y-387956D01*
X217780Y-387253D01*
X217640Y-386551D01*
X217243Y-385956D01*
X216647Y-385558D01*
X215945Y-385418D01*
D02*
G37*
G36*
X265158D02*
X264455Y-385558D01*
X263890Y-385935D01*
X263746Y-385999D01*
X263331D01*
X263304Y-385958D01*
X262708Y-385560D01*
X262006Y-385420D01*
X261304Y-385560D01*
X260708Y-385958D01*
X260311Y-386553D01*
X260171Y-387255D01*
X260311Y-387958D01*
X260708Y-388553D01*
X261304Y-388951D01*
X262006Y-389090D01*
X262708Y-388951D01*
X263273Y-388574D01*
X263417Y-388510D01*
X263832D01*
X263860Y-388551D01*
X264455Y-388949D01*
X265158Y-389089D01*
X265860Y-388949D01*
X266455Y-388551D01*
X266853Y-387956D01*
X266993Y-387253D01*
X266853Y-386551D01*
X266455Y-385956D01*
X265860Y-385558D01*
X265158Y-385418D01*
D02*
G37*
G36*
X246339Y-385140D02*
X245636Y-385279D01*
X245041Y-385677D01*
X244643Y-386273D01*
X244503Y-386975D01*
X244643Y-387677D01*
X245041Y-388273D01*
X245636Y-388671D01*
X246339Y-388810D01*
X247041Y-388671D01*
X247476Y-388380D01*
X248059Y-388472D01*
X248112Y-388551D01*
X248707Y-388949D01*
X249410Y-389089D01*
X250112Y-388949D01*
X250707Y-388551D01*
X251105Y-387956D01*
X251245Y-387253D01*
X251105Y-386551D01*
X250707Y-385956D01*
X250112Y-385558D01*
X249410Y-385418D01*
X248707Y-385558D01*
X248327Y-385812D01*
X247689Y-385756D01*
X247636Y-385677D01*
X247041Y-385279D01*
X246339Y-385140D01*
D02*
G37*
G36*
X181534Y-385922D02*
X180832Y-386061D01*
X180236Y-386459D01*
X179838Y-387055D01*
X179699Y-387757D01*
X179838Y-388459D01*
X180236Y-389055D01*
X180832Y-389453D01*
X181534Y-389592D01*
X182236Y-389453D01*
X182832Y-389055D01*
X183229Y-388459D01*
X183369Y-387757D01*
X183229Y-387055D01*
X182832Y-386459D01*
X182236Y-386061D01*
X181534Y-385922D01*
D02*
G37*
G36*
X0Y-364854D02*
X-2118Y-365020D01*
X-4185Y-365516D01*
X-6148Y-366330D01*
X-7960Y-367440D01*
X-9575Y-368820D01*
X-10955Y-370436D01*
X-12066Y-372248D01*
X-12879Y-374211D01*
X-13375Y-376277D01*
X-13542Y-378395D01*
X-13375Y-380514D01*
X-12879Y-382580D01*
X-12066Y-384543D01*
X-10955Y-386355D01*
X-9575Y-387971D01*
X-7960Y-389351D01*
X-6148Y-390461D01*
X-4185Y-391274D01*
X-2118Y-391770D01*
X0Y-391937D01*
X2118Y-391770D01*
X4185Y-391274D01*
X6148Y-390461D01*
X7960Y-389351D01*
X9576Y-387971D01*
X10955Y-386355D01*
X12066Y-384543D01*
X12879Y-382580D01*
X13375Y-380514D01*
X13542Y-378395D01*
X13375Y-376277D01*
X12879Y-374211D01*
X12066Y-372248D01*
X10955Y-370436D01*
X9576Y-368820D01*
X7960Y-367440D01*
X6148Y-366330D01*
X4185Y-365516D01*
X2118Y-365020D01*
X0Y-364854D01*
D02*
G37*
%LPD*%
D211*
X574409Y7445D02*
D03*
D212*
Y-9055D02*
D03*
D217*
X321260Y-145669D02*
D03*
D236*
X298031Y-145512D02*
D03*
D240*
X608268Y-288779D02*
D03*
Y-271260D02*
D03*
D241*
X620079Y-263583D02*
D03*
Y-296457D02*
D03*
D242*
X354035Y-38976D02*
D03*
X424803D02*
D03*
X535827Y-112205D02*
D03*
D244*
X58268Y-243701D02*
D03*
X218110Y-323622D02*
D03*
D03*
X58268Y-243701D02*
D03*
D246*
X-18464Y-326781D02*
D03*
X1535D02*
D03*
Y-306781D02*
D03*
X-18464D02*
D03*
X-18465Y-273630D02*
D03*
X1535D02*
D03*
Y-253630D02*
D03*
X-18465D02*
D03*
Y-220480D02*
D03*
X1535D02*
D03*
Y-200480D02*
D03*
X-18465D02*
D03*
X-18464Y-167332D02*
D03*
X1535D02*
D03*
Y-147332D02*
D03*
X-18464D02*
D03*
D249*
X609449Y-138189D02*
D03*
X619449D02*
D03*
D250*
X593307Y-292126D02*
D03*
X599044Y-275032D02*
D03*
X585039Y-272835D02*
D03*
X581496D02*
D03*
X541093Y-284626D02*
D03*
X541411Y-269932D02*
D03*
X536489Y-269182D02*
D03*
X554724Y-272441D02*
D03*
X555460Y-284401D02*
D03*
X567525Y-286203D02*
D03*
X581890Y-290158D02*
D03*
X583815Y-275386D02*
D03*
X604724Y-274803D02*
D03*
X320761Y-183851D02*
D03*
X124016Y-110236D02*
D03*
X57422Y-128927D02*
D03*
X89312Y-128140D02*
D03*
X84981D02*
D03*
X80651D02*
D03*
X89312Y-123809D02*
D03*
X84981D02*
D03*
X80651D02*
D03*
X89312Y-119478D02*
D03*
X84981D02*
D03*
X80651D02*
D03*
X58407Y-137589D02*
D03*
X85044Y-139557D02*
D03*
X44134Y-115080D02*
D03*
X58210Y-108061D02*
D03*
X84981Y-108061D02*
D03*
X262724Y-107813D02*
D03*
X253082Y-110236D02*
D03*
X364567Y-326378D02*
D03*
X357575Y-327776D02*
D03*
X357480Y-332677D02*
D03*
X350787Y-329921D02*
D03*
X205906Y-372441D02*
D03*
X211024D02*
D03*
X222835Y-372047D02*
D03*
X217323Y-371654D02*
D03*
X237795D02*
D03*
X242897Y-371864D02*
D03*
X250394Y-375984D02*
D03*
X259449Y-373228D02*
D03*
X268504Y-372047D02*
D03*
X274803Y-372441D02*
D03*
X266929Y-385039D02*
D03*
X243701Y-389370D02*
D03*
X250394Y-384646D02*
D03*
X227953Y-383858D02*
D03*
X233858Y-384646D02*
D03*
X213386D02*
D03*
X24500Y-8429D02*
D03*
X603150Y-235946D02*
D03*
X604316Y-246600D02*
D03*
X152756Y-49606D02*
D03*
X149935Y-124206D02*
D03*
X464961Y-125197D02*
D03*
X50000Y-44094D02*
D03*
X383465Y-234252D02*
D03*
X389764D02*
D03*
X386614Y-237402D02*
D03*
Y-231102D02*
D03*
X26378Y-20472D02*
D03*
X24409Y-16535D02*
D03*
X26378Y-10630D02*
D03*
X230709Y-242913D02*
D03*
X476968Y-76378D02*
D03*
X135433Y-79134D02*
D03*
X428346Y-187795D02*
D03*
X140070Y-132385D02*
D03*
X182677Y-94488D02*
D03*
X189764Y-100787D02*
D03*
X196850Y-94488D02*
D03*
X149803Y-9238D02*
D03*
X150000Y-787D02*
D03*
X474409Y-265748D02*
D03*
X480315Y-259744D02*
D03*
Y-271752D02*
D03*
X478346Y-305118D02*
D03*
X477362Y-313767D02*
D03*
X624938Y-196373D02*
D03*
X624926Y-201353D02*
D03*
X624938Y-206373D02*
D03*
X624918Y-211353D02*
D03*
X625079Y-173898D02*
D03*
X624685Y-163898D02*
D03*
X118110Y-36220D02*
D03*
X117717Y-47293D02*
D03*
X578332Y-261235D02*
D03*
X507874Y-255906D02*
D03*
X534814Y-297190D02*
D03*
X528960Y-296841D02*
D03*
X495276Y-298130D02*
D03*
X503346Y-297967D02*
D03*
X501181Y-298130D02*
D03*
X516929D02*
D03*
X522835Y-297736D02*
D03*
X540945Y-297342D02*
D03*
X546457D02*
D03*
X562205Y-297736D02*
D03*
X568110D02*
D03*
X570472D02*
D03*
X576378D02*
D03*
X564173Y-255906D02*
D03*
X494882Y-262303D02*
D03*
X495669Y-255512D02*
D03*
X209449Y7087D02*
D03*
X203937Y1969D02*
D03*
X214173Y1181D02*
D03*
Y-79134D02*
D03*
X205118Y-79380D02*
D03*
X168504Y-79528D02*
D03*
Y-73622D02*
D03*
Y-71260D02*
D03*
Y-65354D02*
D03*
X168898Y-49606D02*
D03*
Y-44094D02*
D03*
X168504Y-37795D02*
D03*
Y-31890D02*
D03*
Y-25984D02*
D03*
X168110Y-20079D02*
D03*
Y-4331D02*
D03*
X168273Y-6496D02*
D03*
X168110Y1575D02*
D03*
X144095Y-80315D02*
D03*
X87795Y-99606D02*
D03*
X535827Y-345276D02*
D03*
X555512Y-340158D02*
D03*
X568898Y-319009D02*
D03*
X570079Y-309921D02*
D03*
X536221Y-300787D02*
D03*
X505512Y-303150D02*
D03*
X455118Y-92520D02*
D03*
X460236Y-87795D02*
D03*
Y-92520D02*
D03*
X454724Y-87795D02*
D03*
X624409Y-31496D02*
D03*
X620079Y-31890D02*
D03*
X615748Y-32283D02*
D03*
X611417Y-33071D02*
D03*
X620866Y-35827D02*
D03*
X611811Y-38189D02*
D03*
X542913Y-72835D02*
D03*
Y-69291D02*
D03*
Y-65748D02*
D03*
Y-61811D02*
D03*
Y-58268D02*
D03*
X595276Y-79921D02*
D03*
X608405Y-70079D02*
D03*
X238189Y-138976D02*
D03*
X217405Y-138189D02*
D03*
X214173Y-107087D02*
D03*
X192126Y-111811D02*
D03*
X133099Y-119984D02*
D03*
X148425Y-104336D02*
D03*
X153150Y-103412D02*
D03*
X158268Y-107480D02*
D03*
X168110Y-103937D02*
D03*
X161417Y-95276D02*
D03*
Y-107480D02*
D03*
X152398Y-117717D02*
D03*
X156926Y-111614D02*
D03*
X168343Y-110827D02*
D03*
X189209Y-131339D02*
D03*
Y-117480D02*
D03*
X173461Y-127362D02*
D03*
X165587Y-139961D02*
D03*
X151808Y-137205D02*
D03*
X106693Y15354D02*
D03*
X107087Y9449D02*
D03*
X111024D02*
D03*
Y15354D02*
D03*
X105512Y-79921D02*
D03*
X109843D02*
D03*
Y-74410D02*
D03*
X105512D02*
D03*
X99606Y-63779D02*
D03*
X107874D02*
D03*
Y-59842D02*
D03*
X99606D02*
D03*
X74616Y-61723D02*
D03*
X47441Y-5709D02*
D03*
Y-11811D02*
D03*
X75394Y-5709D02*
D03*
Y-11811D02*
D03*
X66142D02*
D03*
X61417D02*
D03*
X56693D02*
D03*
Y-16535D02*
D03*
X61417D02*
D03*
X66142D02*
D03*
Y-21260D02*
D03*
X61417D02*
D03*
X52362Y-35531D02*
D03*
X72795Y-53355D02*
D03*
X84252Y-9055D02*
D03*
Y-5906D02*
D03*
Y-2362D02*
D03*
X88257Y-2500D02*
D03*
X93608Y-3379D02*
D03*
X90158Y-7480D02*
D03*
X97408Y-10197D02*
D03*
X106693Y-27559D02*
D03*
X105282Y-19291D02*
D03*
X383083Y-128504D02*
D03*
X336221Y-122047D02*
D03*
X333465D02*
D03*
X330315Y-121653D02*
D03*
X335827Y-164173D02*
D03*
X333071D02*
D03*
X329919Y-164008D02*
D03*
X329656Y-142480D02*
D03*
X329722Y-145827D02*
D03*
X347638Y-119882D02*
D03*
X347244Y-113189D02*
D03*
X355035Y-105876D02*
D03*
X390654Y-104510D02*
D03*
X383465Y-103543D02*
D03*
X448425Y-165354D02*
D03*
X451968D02*
D03*
X455512D02*
D03*
X458661D02*
D03*
X442815Y-161747D02*
D03*
Y-165847D02*
D03*
X439561D02*
D03*
X425984Y-109843D02*
D03*
X425630Y-112894D02*
D03*
X416535Y-120768D02*
D03*
X423622Y-115354D02*
D03*
X436811Y-153543D02*
D03*
X418110D02*
D03*
X422835D02*
D03*
X427559D02*
D03*
Y-148819D02*
D03*
X418110D02*
D03*
X422835D02*
D03*
Y-144095D02*
D03*
X418110D02*
D03*
X406693Y-125984D02*
D03*
X408268Y-124409D02*
D03*
Y-122047D02*
D03*
X445276Y-103543D02*
D03*
X444488Y-106299D02*
D03*
X440945Y-105905D02*
D03*
X436221Y-106299D02*
D03*
X434347Y-103743D02*
D03*
X434646Y-100787D02*
D03*
X431496Y-100000D02*
D03*
X281890Y-200771D02*
D03*
X288583Y-195276D02*
D03*
X275503D02*
D03*
X356693Y-288583D02*
D03*
X355741Y-296063D02*
D03*
X314961Y-293701D02*
D03*
X320472Y-299569D02*
D03*
Y-287865D02*
D03*
X333465Y-292913D02*
D03*
X339370Y-286162D02*
D03*
Y-298819D02*
D03*
X325590Y-246324D02*
D03*
Y-232344D02*
D03*
X317009Y-239764D02*
D03*
X400000Y-219291D02*
D03*
X398472Y-235531D02*
D03*
X367654Y-236614D02*
D03*
X414772Y-353273D02*
D03*
X460900Y-354061D02*
D03*
X499302Y-353737D02*
D03*
X543718Y-353540D02*
D03*
X605512Y-261024D02*
D03*
Y-256693D02*
D03*
X622835Y-244094D02*
D03*
Y-235433D02*
D03*
X622101Y-250000D02*
D03*
X622803Y-241006D02*
D03*
X619148Y-302756D02*
D03*
X598583Y-353307D02*
D03*
X598898Y-313307D02*
D03*
X22047Y-335433D02*
D03*
X2097Y-349213D02*
D03*
X27067Y-282677D02*
D03*
X5584Y-238905D02*
D03*
X35120Y-228937D02*
D03*
X10630Y-197638D02*
D03*
X19976Y-200787D02*
D03*
Y-220472D02*
D03*
X22441Y-167323D02*
D03*
X19685D02*
D03*
X16929D02*
D03*
X23228Y-147244D02*
D03*
X20079D02*
D03*
X17323D02*
D03*
X27165Y-179134D02*
D03*
X-7874Y-188976D02*
D03*
X364173Y-332283D02*
D03*
X370079D02*
D03*
X377658Y-327985D02*
D03*
X369703Y-326432D02*
D03*
X344882Y-328346D02*
D03*
X348425Y-328740D02*
D03*
X381989Y-348458D02*
D03*
X376870D02*
D03*
X374902D02*
D03*
X370472Y-348425D02*
D03*
X368294Y-348913D02*
D03*
X363878Y-348458D02*
D03*
X361910D02*
D03*
X356792D02*
D03*
X349705Y-348064D02*
D03*
X354823Y-348851D02*
D03*
X156693Y-18110D02*
D03*
X203689Y-248906D02*
D03*
X203937Y-242913D02*
D03*
X451674Y-283940D02*
D03*
X381989Y-331971D02*
D03*
X370178Y-315042D02*
D03*
X342618Y-315081D02*
D03*
X451674Y-234727D02*
D03*
X258702Y-264859D02*
D03*
X445768Y-254381D02*
D03*
X359874Y-183841D02*
D03*
X263322Y-246466D02*
D03*
X340847Y-179215D02*
D03*
X451674Y-244570D02*
D03*
X258760Y-256529D02*
D03*
X445768Y-264255D02*
D03*
X350327Y-183546D02*
D03*
X263622Y-236666D02*
D03*
X352461Y-315042D02*
D03*
X330705Y-179215D02*
D03*
X263122Y-285766D02*
D03*
X364272Y-315042D02*
D03*
X343012Y-332365D02*
D03*
X451674Y-254381D02*
D03*
X350327Y-179215D02*
D03*
X258622Y-246466D02*
D03*
X322933Y-332365D02*
D03*
X445768Y-275261D02*
D03*
X340256Y-183841D02*
D03*
X263580Y-226943D02*
D03*
X445768Y-224885D02*
D03*
X320473Y-179117D02*
D03*
X263322Y-276066D02*
D03*
X352106Y-332482D02*
D03*
X451674Y-264255D02*
D03*
X259022Y-236566D02*
D03*
X322540Y-315042D02*
D03*
X445768Y-283940D02*
D03*
X331091Y-184050D02*
D03*
X258622Y-285766D02*
D03*
X376477Y-315042D02*
D03*
X357973Y-315042D02*
D03*
X445768Y-234727D02*
D03*
X379496Y-183803D02*
D03*
Y-179215D02*
D03*
X262922Y-265040D02*
D03*
X332776Y-332365D02*
D03*
X451674Y-275261D02*
D03*
X369981Y-179215D02*
D03*
X258922Y-226766D02*
D03*
X451674Y-224885D02*
D03*
X360138Y-179215D02*
D03*
X258622Y-276066D02*
D03*
X381595Y-315042D02*
D03*
X445768Y-244570D02*
D03*
X369685Y-183841D02*
D03*
X263681Y-256529D02*
D03*
X332382Y-315042D02*
D03*
X19976Y-252953D02*
D03*
Y-272638D02*
D03*
Y-326772D02*
D03*
Y-307087D02*
D03*
X100729Y-123872D02*
D03*
X163071Y-390730D02*
D03*
X259285Y-390247D02*
D03*
X267204Y-390009D02*
D03*
X216162Y-390947D02*
D03*
X235144Y-390416D02*
D03*
X251456Y-390009D02*
D03*
X226063Y-390722D02*
D03*
X281201Y-390009D02*
D03*
X174941Y-390600D02*
D03*
X202441D02*
D03*
M02*
